G04 ================== begin FILE IDENTIFICATION RECORD ==================*
G04 Layout Name:  14629-1a.brd*
G04 Film Name:    NOTICE*
G04 File Format:  Gerber RS274X*
G04 File Origin:  Cadence Allegro 16.5-S037*
G04 Origin Date:  Tue Nov 25 11:50:47 2014*
G04 *
G04 Layer:  MANUFACTURING/THERMAL*
G04 *
G04 Offset:    (0.00 0.00)*
G04 Mirror:    No*
G04 Mode:      Positive*
G04 Rotation:  0*
G04 FullContactRelief:  No*
G04 UndefLineWidth:     6.00*
G04 ================== end FILE IDENTIFICATION RECORD ====================*
%FSLAX35Y35*MOIN*%
%IR0*IPPOS*OFA0.00000B0.00000*MIA0B0*SFA1.00000B1.00000*%
%ADD10C,.02*%
%ADD11C,.015*%
%ADD12C,.006*%
G75*
%LPD*%
G75*
G36*
G01X58318Y-52018D02*
G02X36772Y-30472I7501J29047D01*
G01X31632Y-30471D01*
G03X58319Y-57158I34187J7500D01*
G01X58318Y-52018D01*
G37*
G36*
G01X36772Y-15471D02*
G02X58318Y6076I29047J-7500D01*
G01X58319Y11216D01*
G03X31632Y-15472I7500J-34187D01*
G01X36772Y-15471D01*
G37*
G36*
G01X113189Y-502090D02*
G02X85630Y-464533I11812J37557D01*
G01Y-448785D01*
X91535D01*
Y-464533D01*
G03X113189Y-495844I33464J0D01*
G01Y-502090D01*
G37*
G36*
G01X85630Y-409415D02*
Y-393667D01*
G02X113189Y-356110I39371J0D01*
G01Y-362356D01*
G03X91535Y-393667I11810J-31311D01*
G01Y-409415D01*
X85630D01*
G37*
G36*
G01X94866Y-30472D02*
G02X73319Y-52018I-29047J7501D01*
G01X73318Y-57158D01*
G03X100006Y-30471I-7499J34187D01*
G01X94866Y-30472D01*
G37*
G36*
G01X73319Y6076D02*
G02X94866Y-15471I-7500J-29047D01*
G01X100006Y-15472D01*
G03X73318Y11216I-34187J-7499D01*
G01X73319Y6076D01*
G37*
G36*
G01X136811Y-502090D02*
Y-495844D01*
G03X158465Y-464533I-11810J31311D01*
G01Y-448785D01*
X164370D01*
Y-464533D01*
G02X136811Y-502090I-39371J0D01*
G37*
G36*
G01X158465Y-409415D02*
Y-393667D01*
G03X136811Y-362356I-33464J0D01*
G01Y-356110D01*
G02X164370Y-393667I-11812J-37557D01*
G01Y-409415D01*
X158465D01*
G37*
G54D10*
G01X-109408Y-660900D02*
Y-648400D01*
X-101492D01*
G01X-104408Y-654442D02*
X-109408D01*
G01X-89950Y-660900D02*
X-91200Y-660692D01*
X-92450Y-659859D01*
X-93284Y-658400D01*
X-93700Y-656733D01*
X-93284Y-655067D01*
X-92450Y-653608D01*
X-91200Y-652775D01*
X-89950Y-652567D01*
X-88700Y-652775D01*
X-87450Y-653608D01*
X-86617Y-655067D01*
X-86408Y-656733D01*
X-86617Y-658400D01*
X-87450Y-659859D01*
X-88700Y-660692D01*
X-89950Y-660900D01*
G01X-77367D02*
Y-652567D01*
G01Y-654233D02*
X-76325Y-653400D01*
X-75283Y-652775D01*
X-73825Y-652567D01*
X-72783Y-652775D01*
X-71533Y-653400D01*
G01X-47408Y-650483D02*
X-46158Y-649234D01*
X-44700Y-648608D01*
X-43033Y-648400D01*
X-40950Y-648817D01*
X-39492Y-649858D01*
X-39075Y-651108D01*
X-39283Y-652359D01*
X-40117Y-653400D01*
X-44283Y-655483D01*
X-46158Y-656942D01*
X-47408Y-659025D01*
X-47825Y-660900D01*
X-39075D01*
G01X-28367D02*
X-27950Y-658192D01*
X-27325Y-655900D01*
X-26492Y-653817D01*
X-25450Y-651525D01*
X-23783Y-648400D01*
X-32117D01*
G01X-9950Y-660900D02*
Y-648400D01*
X-17659Y-657358D01*
X-7241D01*
G01X-1325Y-660900D02*
X7425Y-648400D01*
G01X-1325D02*
X7425Y-660900D01*
G01X31133Y-664025D02*
X32592Y-664858D01*
X34258Y-665067D01*
X35717Y-664858D01*
X36967Y-663817D01*
X37800Y-662358D01*
Y-652567D01*
G01Y-654233D02*
X36967Y-653400D01*
X35717Y-652775D01*
X34258Y-652567D01*
X32592Y-652983D01*
X31550Y-653817D01*
X30716Y-655275D01*
X30300Y-656733D01*
X30508Y-657984D01*
X31342Y-659442D01*
X32592Y-660483D01*
X34258Y-660900D01*
X35508Y-660692D01*
X36967Y-659859D01*
X37800Y-659025D01*
G01X46425Y-655275D02*
X53092D01*
X52467Y-653817D01*
X51425Y-652983D01*
X49967Y-652567D01*
X48508Y-652775D01*
X47258Y-653400D01*
X46425Y-654858D01*
X46008Y-656109D01*
Y-657358D01*
X46425Y-658608D01*
X47467Y-659859D01*
X48717Y-660692D01*
X50175Y-660900D01*
X51633Y-660483D01*
X53092Y-659234D01*
G01X62133Y-660900D02*
Y-652567D01*
G01Y-654233D02*
X63175Y-653400D01*
X64217Y-652775D01*
X65675Y-652567D01*
X66717Y-652775D01*
X67967Y-653400D01*
G01X76800Y-660900D02*
Y-648400D01*
G01Y-654650D02*
X77842Y-653400D01*
X79092Y-652775D01*
X80342Y-652567D01*
X82217Y-652983D01*
X83467Y-653817D01*
X84300Y-655275D01*
Y-656942D01*
X83883Y-658608D01*
X83050Y-659859D01*
X81592Y-660692D01*
X80342Y-660900D01*
X79092Y-660692D01*
X77842Y-660067D01*
X76800Y-659025D01*
G01X92925Y-655275D02*
X99592D01*
X98967Y-653817D01*
X97925Y-652983D01*
X96467Y-652567D01*
X95008Y-652775D01*
X93758Y-653400D01*
X92925Y-654858D01*
X92508Y-656109D01*
Y-657358D01*
X92925Y-658608D01*
X93967Y-659859D01*
X95217Y-660692D01*
X96675Y-660900D01*
X98133Y-660483D01*
X99592Y-659234D01*
G01X108633Y-660900D02*
Y-652567D01*
G01Y-654233D02*
X109675Y-653400D01*
X110717Y-652775D01*
X112175Y-652567D01*
X113217Y-652775D01*
X114467Y-653400D01*
G01X141300Y-660900D02*
Y-650275D01*
X141717Y-649234D01*
X142550Y-648608D01*
X143800Y-648400D01*
X145050Y-648817D01*
X145675Y-649858D01*
G01X143175Y-653400D02*
X139008D01*
G01X158050Y-660900D02*
X156800Y-660692D01*
X155550Y-659859D01*
X154716Y-658400D01*
X154300Y-656733D01*
X154716Y-655067D01*
X155550Y-653608D01*
X156800Y-652775D01*
X158050Y-652567D01*
X159300Y-652775D01*
X160550Y-653608D01*
X161383Y-655067D01*
X161592Y-656733D01*
X161383Y-658400D01*
X160550Y-659859D01*
X159300Y-660692D01*
X158050Y-660900D01*
G01X170633D02*
Y-652567D01*
G01Y-654233D02*
X171675Y-653400D01*
X172717Y-652775D01*
X174175Y-652567D01*
X175217Y-652775D01*
X176467Y-653400D01*
G01X182800Y-660900D02*
Y-652567D01*
G01Y-654858D02*
X183425Y-653817D01*
X184467Y-652983D01*
X185925Y-652567D01*
X187383Y-652983D01*
X188425Y-653817D01*
X189050Y-654858D01*
Y-660900D01*
G01Y-654858D02*
X189675Y-653817D01*
X190717Y-652983D01*
X192175Y-652567D01*
X193633Y-652983D01*
X194675Y-653817D01*
X195300Y-655067D01*
Y-660900D01*
G01X208300D02*
Y-652567D01*
G01Y-654025D02*
X207467Y-653192D01*
X206217Y-652775D01*
X204758Y-652567D01*
X203300Y-652983D01*
X202050Y-653817D01*
X201216Y-655067D01*
X200800Y-656733D01*
X201216Y-658400D01*
X202050Y-659650D01*
X203300Y-660483D01*
X204758Y-660900D01*
X206217Y-660692D01*
X207467Y-660067D01*
X208300Y-659234D01*
G01X220050Y-648400D02*
Y-660900D01*
G01X217133Y-652567D02*
X222967D01*
G01X251050Y-648400D02*
Y-660900D01*
G01X248133Y-652567D02*
X253967D01*
G01X263008Y-660900D02*
Y-648400D01*
G01Y-654442D02*
X264050Y-653400D01*
X265092Y-652775D01*
X266758Y-652567D01*
X268008Y-652775D01*
X269467Y-653608D01*
X270092Y-654858D01*
Y-660900D01*
G01X278925Y-655275D02*
X285592D01*
X284967Y-653817D01*
X283925Y-652983D01*
X282467Y-652567D01*
X281008Y-652775D01*
X279758Y-653400D01*
X278925Y-654858D01*
X278508Y-656109D01*
Y-657358D01*
X278925Y-658608D01*
X279967Y-659859D01*
X281217Y-660692D01*
X282675Y-660900D01*
X284133Y-660483D01*
X285592Y-659234D01*
G01X294633Y-660900D02*
Y-652567D01*
G01Y-654233D02*
X295675Y-653400D01*
X296717Y-652775D01*
X298175Y-652567D01*
X299217Y-652775D01*
X300467Y-653400D01*
G01X306800Y-660900D02*
Y-652567D01*
G01Y-654858D02*
X307425Y-653817D01*
X308467Y-652983D01*
X309925Y-652567D01*
X311383Y-652983D01*
X312425Y-653817D01*
X313050Y-654858D01*
Y-660900D01*
G01Y-654858D02*
X313675Y-653817D01*
X314717Y-652983D01*
X316175Y-652567D01*
X317633Y-652983D01*
X318675Y-653817D01*
X319300Y-655067D01*
Y-660900D01*
G01X332300D02*
Y-652567D01*
G01Y-654025D02*
X331467Y-653192D01*
X330217Y-652775D01*
X328758Y-652567D01*
X327300Y-652983D01*
X326050Y-653817D01*
X325216Y-655067D01*
X324800Y-656733D01*
X325216Y-658400D01*
X326050Y-659650D01*
X327300Y-660483D01*
X328758Y-660900D01*
X330217Y-660692D01*
X331467Y-660067D01*
X332300Y-659234D01*
G01X344050Y-660900D02*
Y-648400D01*
G01X372133Y-660900D02*
Y-652567D01*
G01Y-654233D02*
X373175Y-653400D01*
X374217Y-652775D01*
X375675Y-652567D01*
X376717Y-652775D01*
X377967Y-653400D01*
G01X387425Y-655275D02*
X394092D01*
X393467Y-653817D01*
X392425Y-652983D01*
X390967Y-652567D01*
X389508Y-652775D01*
X388258Y-653400D01*
X387425Y-654858D01*
X387008Y-656109D01*
Y-657358D01*
X387425Y-658608D01*
X388467Y-659859D01*
X389717Y-660692D01*
X391175Y-660900D01*
X392633Y-660483D01*
X394092Y-659234D01*
G01X406050Y-660900D02*
Y-648400D01*
G01X421550Y-652567D02*
Y-660900D01*
G01Y-649234D02*
X421133Y-649025D01*
Y-648608D01*
X421550Y-648400D01*
X421967Y-648608D01*
Y-649025D01*
X421550Y-649234D01*
G01X433925Y-655275D02*
X440592D01*
X439967Y-653817D01*
X438925Y-652983D01*
X437467Y-652567D01*
X436008Y-652775D01*
X434758Y-653400D01*
X433925Y-654858D01*
X433508Y-656109D01*
Y-657358D01*
X433925Y-658608D01*
X434967Y-659859D01*
X436217Y-660692D01*
X437675Y-660900D01*
X439133Y-660483D01*
X440592Y-659234D01*
G01X451300Y-660900D02*
Y-650275D01*
X451717Y-649234D01*
X452550Y-648608D01*
X453800Y-648400D01*
X455050Y-648817D01*
X455675Y-649858D01*
G01X453175Y-653400D02*
X449008D01*
G01X-106700Y-682600D02*
Y-671975D01*
X-106283Y-670934D01*
X-105450Y-670308D01*
X-104200Y-670100D01*
X-102950Y-670517D01*
X-102325Y-671558D01*
G01X-104825Y-675100D02*
X-108992D01*
G01X-89950Y-682600D02*
X-91200Y-682392D01*
X-92450Y-681559D01*
X-93284Y-680100D01*
X-93700Y-678433D01*
X-93284Y-676767D01*
X-92450Y-675308D01*
X-91200Y-674475D01*
X-89950Y-674267D01*
X-88700Y-674475D01*
X-87450Y-675308D01*
X-86617Y-676767D01*
X-86408Y-678433D01*
X-86617Y-680100D01*
X-87450Y-681559D01*
X-88700Y-682392D01*
X-89950Y-682600D01*
G01X-74450D02*
Y-670100D01*
G01X-58950Y-682600D02*
Y-670100D01*
G01X-43450Y-682600D02*
X-44700Y-682392D01*
X-45950Y-681559D01*
X-46784Y-680100D01*
X-47200Y-678433D01*
X-46784Y-676767D01*
X-45950Y-675308D01*
X-44700Y-674475D01*
X-43450Y-674267D01*
X-42200Y-674475D01*
X-40950Y-675308D01*
X-40117Y-676767D01*
X-39908Y-678433D01*
X-40117Y-680100D01*
X-40950Y-681559D01*
X-42200Y-682392D01*
X-43450Y-682600D01*
G01X-33159Y-674267D02*
X-30658Y-682600D01*
X-27950Y-674267D01*
X-25242Y-682600D01*
X-22741Y-674267D01*
G01X133Y-685725D02*
X1592Y-686558D01*
X3258Y-686767D01*
X4717Y-686558D01*
X5967Y-685517D01*
X6800Y-684058D01*
Y-674267D01*
G01Y-675933D02*
X5967Y-675100D01*
X4717Y-674475D01*
X3258Y-674267D01*
X1592Y-674683D01*
X550Y-675517D01*
X-284Y-676975D01*
X-700Y-678433D01*
X-492Y-679684D01*
X342Y-681142D01*
X1592Y-682183D01*
X3258Y-682600D01*
X4508Y-682392D01*
X5967Y-681559D01*
X6800Y-680725D01*
G01X15425Y-676975D02*
X22092D01*
X21467Y-675517D01*
X20425Y-674683D01*
X18967Y-674267D01*
X17508Y-674475D01*
X16258Y-675100D01*
X15425Y-676558D01*
X15008Y-677809D01*
Y-679058D01*
X15425Y-680308D01*
X16467Y-681559D01*
X17717Y-682392D01*
X19175Y-682600D01*
X20633Y-682183D01*
X22092Y-680934D01*
G01X31133Y-682600D02*
Y-674267D01*
G01Y-675933D02*
X32175Y-675100D01*
X33217Y-674475D01*
X34675Y-674267D01*
X35717Y-674475D01*
X36967Y-675100D01*
G01X45800Y-682600D02*
Y-670100D01*
G01Y-676350D02*
X46842Y-675100D01*
X48092Y-674475D01*
X49342Y-674267D01*
X51217Y-674683D01*
X52467Y-675517D01*
X53300Y-676975D01*
Y-678642D01*
X52883Y-680308D01*
X52050Y-681559D01*
X50592Y-682392D01*
X49342Y-682600D01*
X48092Y-682392D01*
X46842Y-681767D01*
X45800Y-680725D01*
G01X61925Y-676975D02*
X68592D01*
X67967Y-675517D01*
X66925Y-674683D01*
X65467Y-674267D01*
X64008Y-674475D01*
X62758Y-675100D01*
X61925Y-676558D01*
X61508Y-677809D01*
Y-679058D01*
X61925Y-680308D01*
X62967Y-681559D01*
X64217Y-682392D01*
X65675Y-682600D01*
X67133Y-682183D01*
X68592Y-680934D01*
G01X77633Y-682600D02*
Y-674267D01*
G01Y-675933D02*
X78675Y-675100D01*
X79717Y-674475D01*
X81175Y-674267D01*
X82217Y-674475D01*
X83467Y-675100D01*
G01X115300Y-670100D02*
Y-682600D01*
G01Y-680725D02*
X114467Y-681767D01*
X113217Y-682392D01*
X111758Y-682600D01*
X110092Y-682183D01*
X108842Y-681142D01*
X108008Y-679892D01*
X107800Y-678433D01*
X108008Y-676975D01*
X108842Y-675725D01*
X110092Y-674683D01*
X111758Y-674267D01*
X113217Y-674475D01*
X114258Y-674892D01*
X115300Y-675725D01*
G01X123925Y-676975D02*
X130592D01*
X129967Y-675517D01*
X128925Y-674683D01*
X127467Y-674267D01*
X126008Y-674475D01*
X124758Y-675100D01*
X123925Y-676558D01*
X123508Y-677809D01*
Y-679058D01*
X123925Y-680308D01*
X124967Y-681559D01*
X126217Y-682392D01*
X127675Y-682600D01*
X129133Y-682183D01*
X130592Y-680934D01*
G01X139425Y-681142D02*
X140467Y-681975D01*
X141925Y-682600D01*
X143175D01*
X144425Y-682183D01*
X145258Y-681559D01*
X145675Y-680725D01*
X145467Y-679475D01*
X144633Y-678850D01*
X140883Y-677600D01*
X140050Y-676142D01*
X140467Y-675100D01*
X141300Y-674475D01*
X142550Y-674267D01*
X143800Y-674475D01*
X145050Y-675100D01*
G01X158050Y-674267D02*
Y-682600D01*
G01Y-670934D02*
X157633Y-670725D01*
Y-670308D01*
X158050Y-670100D01*
X158467Y-670308D01*
Y-670725D01*
X158050Y-670934D01*
G01X170633Y-685725D02*
X172092Y-686558D01*
X173758Y-686767D01*
X175217Y-686558D01*
X176467Y-685517D01*
X177300Y-684058D01*
Y-674267D01*
G01Y-675933D02*
X176467Y-675100D01*
X175217Y-674475D01*
X173758Y-674267D01*
X172092Y-674683D01*
X171050Y-675517D01*
X170216Y-676975D01*
X169800Y-678433D01*
X170008Y-679684D01*
X170842Y-681142D01*
X172092Y-682183D01*
X173758Y-682600D01*
X175008Y-682392D01*
X176467Y-681559D01*
X177300Y-680725D01*
G01X185508Y-682600D02*
Y-674267D01*
G01Y-676350D02*
X186342Y-675308D01*
X187592Y-674475D01*
X189258Y-674267D01*
X190717Y-674475D01*
X191967Y-675308D01*
X192592Y-676767D01*
Y-682600D01*
G01X-99808Y-207000D02*
Y-194500D01*
X-91892D01*
G01X-94808Y-200542D02*
X-99808D01*
G01X-80350Y-207000D02*
X-81600Y-206792D01*
X-82850Y-205959D01*
X-83684Y-204500D01*
X-84100Y-202833D01*
X-83684Y-201167D01*
X-82850Y-199708D01*
X-81600Y-198875D01*
X-80350Y-198667D01*
X-79100Y-198875D01*
X-77850Y-199708D01*
X-77017Y-201167D01*
X-76808Y-202833D01*
X-77017Y-204500D01*
X-77850Y-205959D01*
X-79100Y-206792D01*
X-80350Y-207000D01*
G01X-67767D02*
Y-198667D01*
G01Y-200333D02*
X-66725Y-199500D01*
X-65683Y-198875D01*
X-64225Y-198667D01*
X-63183Y-198875D01*
X-61933Y-199500D01*
G01X-37808Y-196583D02*
X-36558Y-195334D01*
X-35100Y-194708D01*
X-33433Y-194500D01*
X-31350Y-194917D01*
X-29892Y-195958D01*
X-29475Y-197208D01*
X-29683Y-198459D01*
X-30517Y-199500D01*
X-34683Y-201583D01*
X-36558Y-203042D01*
X-37808Y-205125D01*
X-38225Y-207000D01*
X-29475D01*
G01X-18767D02*
X-18350Y-204292D01*
X-17725Y-202000D01*
X-16892Y-199917D01*
X-15850Y-197625D01*
X-14183Y-194500D01*
X-22517D01*
G01X-350Y-207000D02*
Y-194500D01*
X-8059Y-203458D01*
X2359D01*
G01X8275Y-207000D02*
X17025Y-194500D01*
G01X8275D02*
X17025Y-207000D01*
G01X40733Y-210125D02*
X42192Y-210958D01*
X43858Y-211167D01*
X45317Y-210958D01*
X46567Y-209917D01*
X47400Y-208458D01*
Y-198667D01*
G01Y-200333D02*
X46567Y-199500D01*
X45317Y-198875D01*
X43858Y-198667D01*
X42192Y-199083D01*
X41150Y-199917D01*
X40316Y-201375D01*
X39900Y-202833D01*
X40108Y-204084D01*
X40942Y-205542D01*
X42192Y-206583D01*
X43858Y-207000D01*
X45108Y-206792D01*
X46567Y-205959D01*
X47400Y-205125D01*
G01X56025Y-201375D02*
X62692D01*
X62067Y-199917D01*
X61025Y-199083D01*
X59567Y-198667D01*
X58108Y-198875D01*
X56858Y-199500D01*
X56025Y-200958D01*
X55608Y-202209D01*
Y-203458D01*
X56025Y-204708D01*
X57067Y-205959D01*
X58317Y-206792D01*
X59775Y-207000D01*
X61233Y-206583D01*
X62692Y-205334D01*
G01X71733Y-207000D02*
Y-198667D01*
G01Y-200333D02*
X72775Y-199500D01*
X73817Y-198875D01*
X75275Y-198667D01*
X76317Y-198875D01*
X77567Y-199500D01*
G01X86400Y-207000D02*
Y-194500D01*
G01Y-200750D02*
X87442Y-199500D01*
X88692Y-198875D01*
X89942Y-198667D01*
X91817Y-199083D01*
X93067Y-199917D01*
X93900Y-201375D01*
Y-203042D01*
X93483Y-204708D01*
X92650Y-205959D01*
X91192Y-206792D01*
X89942Y-207000D01*
X88692Y-206792D01*
X87442Y-206167D01*
X86400Y-205125D01*
G01X102525Y-201375D02*
X109192D01*
X108567Y-199917D01*
X107525Y-199083D01*
X106067Y-198667D01*
X104608Y-198875D01*
X103358Y-199500D01*
X102525Y-200958D01*
X102108Y-202209D01*
Y-203458D01*
X102525Y-204708D01*
X103567Y-205959D01*
X104817Y-206792D01*
X106275Y-207000D01*
X107733Y-206583D01*
X109192Y-205334D01*
G01X118233Y-207000D02*
Y-198667D01*
G01Y-200333D02*
X119275Y-199500D01*
X120317Y-198875D01*
X121775Y-198667D01*
X122817Y-198875D01*
X124067Y-199500D01*
G01X150900Y-207000D02*
Y-196375D01*
X151317Y-195334D01*
X152150Y-194708D01*
X153400Y-194500D01*
X154650Y-194917D01*
X155275Y-195958D01*
G01X152775Y-199500D02*
X148608D01*
G01X167650Y-207000D02*
X166400Y-206792D01*
X165150Y-205959D01*
X164316Y-204500D01*
X163900Y-202833D01*
X164316Y-201167D01*
X165150Y-199708D01*
X166400Y-198875D01*
X167650Y-198667D01*
X168900Y-198875D01*
X170150Y-199708D01*
X170983Y-201167D01*
X171192Y-202833D01*
X170983Y-204500D01*
X170150Y-205959D01*
X168900Y-206792D01*
X167650Y-207000D01*
G01X180233D02*
Y-198667D01*
G01Y-200333D02*
X181275Y-199500D01*
X182317Y-198875D01*
X183775Y-198667D01*
X184817Y-198875D01*
X186067Y-199500D01*
G01X192400Y-207000D02*
Y-198667D01*
G01Y-200958D02*
X193025Y-199917D01*
X194067Y-199083D01*
X195525Y-198667D01*
X196983Y-199083D01*
X198025Y-199917D01*
X198650Y-200958D01*
Y-207000D01*
G01Y-200958D02*
X199275Y-199917D01*
X200317Y-199083D01*
X201775Y-198667D01*
X203233Y-199083D01*
X204275Y-199917D01*
X204900Y-201167D01*
Y-207000D01*
G01X217900D02*
Y-198667D01*
G01Y-200125D02*
X217067Y-199292D01*
X215817Y-198875D01*
X214358Y-198667D01*
X212900Y-199083D01*
X211650Y-199917D01*
X210816Y-201167D01*
X210400Y-202833D01*
X210816Y-204500D01*
X211650Y-205750D01*
X212900Y-206583D01*
X214358Y-207000D01*
X215817Y-206792D01*
X217067Y-206167D01*
X217900Y-205334D01*
G01X229650Y-194500D02*
Y-207000D01*
G01X226733Y-198667D02*
X232567D01*
G01X260650Y-194500D02*
Y-207000D01*
G01X257733Y-198667D02*
X263567D01*
G01X272608Y-207000D02*
Y-194500D01*
G01Y-200542D02*
X273650Y-199500D01*
X274692Y-198875D01*
X276358Y-198667D01*
X277608Y-198875D01*
X279067Y-199708D01*
X279692Y-200958D01*
Y-207000D01*
G01X288525Y-201375D02*
X295192D01*
X294567Y-199917D01*
X293525Y-199083D01*
X292067Y-198667D01*
X290608Y-198875D01*
X289358Y-199500D01*
X288525Y-200958D01*
X288108Y-202209D01*
Y-203458D01*
X288525Y-204708D01*
X289567Y-205959D01*
X290817Y-206792D01*
X292275Y-207000D01*
X293733Y-206583D01*
X295192Y-205334D01*
G01X304233Y-207000D02*
Y-198667D01*
G01Y-200333D02*
X305275Y-199500D01*
X306317Y-198875D01*
X307775Y-198667D01*
X308817Y-198875D01*
X310067Y-199500D01*
G01X316400Y-207000D02*
Y-198667D01*
G01Y-200958D02*
X317025Y-199917D01*
X318067Y-199083D01*
X319525Y-198667D01*
X320983Y-199083D01*
X322025Y-199917D01*
X322650Y-200958D01*
Y-207000D01*
G01Y-200958D02*
X323275Y-199917D01*
X324317Y-199083D01*
X325775Y-198667D01*
X327233Y-199083D01*
X328275Y-199917D01*
X328900Y-201167D01*
Y-207000D01*
G01X341900D02*
Y-198667D01*
G01Y-200125D02*
X341067Y-199292D01*
X339817Y-198875D01*
X338358Y-198667D01*
X336900Y-199083D01*
X335650Y-199917D01*
X334816Y-201167D01*
X334400Y-202833D01*
X334816Y-204500D01*
X335650Y-205750D01*
X336900Y-206583D01*
X338358Y-207000D01*
X339817Y-206792D01*
X341067Y-206167D01*
X341900Y-205334D01*
G01X353650Y-207000D02*
Y-194500D01*
G01X381733Y-207000D02*
Y-198667D01*
G01Y-200333D02*
X382775Y-199500D01*
X383817Y-198875D01*
X385275Y-198667D01*
X386317Y-198875D01*
X387567Y-199500D01*
G01X397025Y-201375D02*
X403692D01*
X403067Y-199917D01*
X402025Y-199083D01*
X400567Y-198667D01*
X399108Y-198875D01*
X397858Y-199500D01*
X397025Y-200958D01*
X396608Y-202209D01*
Y-203458D01*
X397025Y-204708D01*
X398067Y-205959D01*
X399317Y-206792D01*
X400775Y-207000D01*
X402233Y-206583D01*
X403692Y-205334D01*
G01X415650Y-207000D02*
Y-194500D01*
G01X431150Y-198667D02*
Y-207000D01*
G01Y-195334D02*
X430733Y-195125D01*
Y-194708D01*
X431150Y-194500D01*
X431567Y-194708D01*
Y-195125D01*
X431150Y-195334D01*
G01X443525Y-201375D02*
X450192D01*
X449567Y-199917D01*
X448525Y-199083D01*
X447067Y-198667D01*
X445608Y-198875D01*
X444358Y-199500D01*
X443525Y-200958D01*
X443108Y-202209D01*
Y-203458D01*
X443525Y-204708D01*
X444567Y-205959D01*
X445817Y-206792D01*
X447275Y-207000D01*
X448733Y-206583D01*
X450192Y-205334D01*
G01X460900Y-207000D02*
Y-196375D01*
X461317Y-195334D01*
X462150Y-194708D01*
X463400Y-194500D01*
X464650Y-194917D01*
X465275Y-195958D01*
G01X462775Y-199500D02*
X458608D01*
G01X-97100Y-228700D02*
Y-218075D01*
X-96683Y-217034D01*
X-95850Y-216408D01*
X-94600Y-216200D01*
X-93350Y-216617D01*
X-92725Y-217658D01*
G01X-95225Y-221200D02*
X-99392D01*
G01X-80350Y-228700D02*
X-81600Y-228492D01*
X-82850Y-227659D01*
X-83684Y-226200D01*
X-84100Y-224533D01*
X-83684Y-222867D01*
X-82850Y-221408D01*
X-81600Y-220575D01*
X-80350Y-220367D01*
X-79100Y-220575D01*
X-77850Y-221408D01*
X-77017Y-222867D01*
X-76808Y-224533D01*
X-77017Y-226200D01*
X-77850Y-227659D01*
X-79100Y-228492D01*
X-80350Y-228700D01*
G01X-64850D02*
Y-216200D01*
G01X-49350Y-228700D02*
Y-216200D01*
G01X-33850Y-228700D02*
X-35100Y-228492D01*
X-36350Y-227659D01*
X-37184Y-226200D01*
X-37600Y-224533D01*
X-37184Y-222867D01*
X-36350Y-221408D01*
X-35100Y-220575D01*
X-33850Y-220367D01*
X-32600Y-220575D01*
X-31350Y-221408D01*
X-30517Y-222867D01*
X-30308Y-224533D01*
X-30517Y-226200D01*
X-31350Y-227659D01*
X-32600Y-228492D01*
X-33850Y-228700D01*
G01X-23559Y-220367D02*
X-21058Y-228700D01*
X-18350Y-220367D01*
X-15642Y-228700D01*
X-13141Y-220367D01*
G01X9733Y-231825D02*
X11192Y-232658D01*
X12858Y-232867D01*
X14317Y-232658D01*
X15567Y-231617D01*
X16400Y-230158D01*
Y-220367D01*
G01Y-222033D02*
X15567Y-221200D01*
X14317Y-220575D01*
X12858Y-220367D01*
X11192Y-220783D01*
X10150Y-221617D01*
X9316Y-223075D01*
X8900Y-224533D01*
X9108Y-225784D01*
X9942Y-227242D01*
X11192Y-228283D01*
X12858Y-228700D01*
X14108Y-228492D01*
X15567Y-227659D01*
X16400Y-226825D01*
G01X25025Y-223075D02*
X31692D01*
X31067Y-221617D01*
X30025Y-220783D01*
X28567Y-220367D01*
X27108Y-220575D01*
X25858Y-221200D01*
X25025Y-222658D01*
X24608Y-223909D01*
Y-225158D01*
X25025Y-226408D01*
X26067Y-227659D01*
X27317Y-228492D01*
X28775Y-228700D01*
X30233Y-228283D01*
X31692Y-227034D01*
G01X40733Y-228700D02*
Y-220367D01*
G01Y-222033D02*
X41775Y-221200D01*
X42817Y-220575D01*
X44275Y-220367D01*
X45317Y-220575D01*
X46567Y-221200D01*
G01X55400Y-228700D02*
Y-216200D01*
G01Y-222450D02*
X56442Y-221200D01*
X57692Y-220575D01*
X58942Y-220367D01*
X60817Y-220783D01*
X62067Y-221617D01*
X62900Y-223075D01*
Y-224742D01*
X62483Y-226408D01*
X61650Y-227659D01*
X60192Y-228492D01*
X58942Y-228700D01*
X57692Y-228492D01*
X56442Y-227867D01*
X55400Y-226825D01*
G01X71525Y-223075D02*
X78192D01*
X77567Y-221617D01*
X76525Y-220783D01*
X75067Y-220367D01*
X73608Y-220575D01*
X72358Y-221200D01*
X71525Y-222658D01*
X71108Y-223909D01*
Y-225158D01*
X71525Y-226408D01*
X72567Y-227659D01*
X73817Y-228492D01*
X75275Y-228700D01*
X76733Y-228283D01*
X78192Y-227034D01*
G01X87233Y-228700D02*
Y-220367D01*
G01Y-222033D02*
X88275Y-221200D01*
X89317Y-220575D01*
X90775Y-220367D01*
X91817Y-220575D01*
X93067Y-221200D01*
G01X124900Y-216200D02*
Y-228700D01*
G01Y-226825D02*
X124067Y-227867D01*
X122817Y-228492D01*
X121358Y-228700D01*
X119692Y-228283D01*
X118442Y-227242D01*
X117608Y-225992D01*
X117400Y-224533D01*
X117608Y-223075D01*
X118442Y-221825D01*
X119692Y-220783D01*
X121358Y-220367D01*
X122817Y-220575D01*
X123858Y-220992D01*
X124900Y-221825D01*
G01X133525Y-223075D02*
X140192D01*
X139567Y-221617D01*
X138525Y-220783D01*
X137067Y-220367D01*
X135608Y-220575D01*
X134358Y-221200D01*
X133525Y-222658D01*
X133108Y-223909D01*
Y-225158D01*
X133525Y-226408D01*
X134567Y-227659D01*
X135817Y-228492D01*
X137275Y-228700D01*
X138733Y-228283D01*
X140192Y-227034D01*
G01X149025Y-227242D02*
X150067Y-228075D01*
X151525Y-228700D01*
X152775D01*
X154025Y-228283D01*
X154858Y-227659D01*
X155275Y-226825D01*
X155067Y-225575D01*
X154233Y-224950D01*
X150483Y-223700D01*
X149650Y-222242D01*
X150067Y-221200D01*
X150900Y-220575D01*
X152150Y-220367D01*
X153400Y-220575D01*
X154650Y-221200D01*
G01X167650Y-220367D02*
Y-228700D01*
G01Y-217034D02*
X167233Y-216825D01*
Y-216408D01*
X167650Y-216200D01*
X168067Y-216408D01*
Y-216825D01*
X167650Y-217034D01*
G01X180233Y-231825D02*
X181692Y-232658D01*
X183358Y-232867D01*
X184817Y-232658D01*
X186067Y-231617D01*
X186900Y-230158D01*
Y-220367D01*
G01Y-222033D02*
X186067Y-221200D01*
X184817Y-220575D01*
X183358Y-220367D01*
X181692Y-220783D01*
X180650Y-221617D01*
X179816Y-223075D01*
X179400Y-224533D01*
X179608Y-225784D01*
X180442Y-227242D01*
X181692Y-228283D01*
X183358Y-228700D01*
X184608Y-228492D01*
X186067Y-227659D01*
X186900Y-226825D01*
G01X195108Y-228700D02*
Y-220367D01*
G01Y-222450D02*
X195942Y-221408D01*
X197192Y-220575D01*
X198858Y-220367D01*
X200317Y-220575D01*
X201567Y-221408D01*
X202192Y-222867D01*
Y-228700D01*
G01X-29933Y92900D02*
Y105400D01*
X-25767D01*
X-24100Y104775D01*
X-22850Y103942D01*
X-21808Y102692D01*
X-20975Y101233D01*
X-20767Y99150D01*
X-20975Y97067D01*
X-21808Y95608D01*
X-22850Y94358D01*
X-24100Y93525D01*
X-25767Y92900D01*
X-29933D01*
G01X-12975Y98525D02*
X-6308D01*
X-6933Y99983D01*
X-7975Y100817D01*
X-9433Y101233D01*
X-10892Y101025D01*
X-12142Y100400D01*
X-12975Y98942D01*
X-13392Y97691D01*
Y96442D01*
X-12975Y95192D01*
X-11933Y93941D01*
X-10683Y93108D01*
X-9225Y92900D01*
X-7767Y93317D01*
X-6308Y94566D01*
G01X4400Y92900D02*
Y103525D01*
X4817Y104566D01*
X5650Y105192D01*
X6900Y105400D01*
X8150Y104983D01*
X8775Y103942D01*
G01X6275Y100400D02*
X2108D01*
G01X21150Y101233D02*
Y92900D01*
G01Y104566D02*
X20733Y104775D01*
Y105192D01*
X21150Y105400D01*
X21567Y105192D01*
Y104775D01*
X21150Y104566D01*
G01X33108Y92900D02*
Y101233D01*
G01Y99150D02*
X33942Y100192D01*
X35192Y101025D01*
X36858Y101233D01*
X38317Y101025D01*
X39567Y100192D01*
X40192Y98733D01*
Y92900D01*
G01X49025Y98525D02*
X55692D01*
X55067Y99983D01*
X54025Y100817D01*
X52567Y101233D01*
X51108Y101025D01*
X49858Y100400D01*
X49025Y98942D01*
X48608Y97691D01*
Y96442D01*
X49025Y95192D01*
X50067Y93941D01*
X51317Y93108D01*
X52775Y92900D01*
X54233Y93317D01*
X55692Y94566D01*
G01X83150Y105400D02*
Y92900D01*
G01X80233Y101233D02*
X86067D01*
G01X95108Y92900D02*
Y105400D01*
G01Y99358D02*
X96150Y100400D01*
X97192Y101025D01*
X98858Y101233D01*
X100108Y101025D01*
X101567Y100192D01*
X102192Y98942D01*
Y92900D01*
G01X111025Y98525D02*
X117692D01*
X117067Y99983D01*
X116025Y100817D01*
X114567Y101233D01*
X113108Y101025D01*
X111858Y100400D01*
X111025Y98942D01*
X110608Y97691D01*
Y96442D01*
X111025Y95192D01*
X112067Y93941D01*
X113317Y93108D01*
X114775Y92900D01*
X116233Y93317D01*
X117692Y94566D01*
G01X126733Y92900D02*
Y101233D01*
G01Y99567D02*
X127775Y100400D01*
X128817Y101025D01*
X130275Y101233D01*
X131317Y101025D01*
X132567Y100400D01*
G01X138900Y92900D02*
Y101233D01*
G01Y98942D02*
X139525Y99983D01*
X140567Y100817D01*
X142025Y101233D01*
X143483Y100817D01*
X144525Y99983D01*
X145150Y98942D01*
Y92900D01*
G01Y98942D02*
X145775Y99983D01*
X146817Y100817D01*
X148275Y101233D01*
X149733Y100817D01*
X150775Y99983D01*
X151400Y98733D01*
Y92900D01*
G01X164400D02*
Y101233D01*
G01Y99775D02*
X163567Y100608D01*
X162317Y101025D01*
X160858Y101233D01*
X159400Y100817D01*
X158150Y99983D01*
X157316Y98733D01*
X156900Y97067D01*
X157316Y95400D01*
X158150Y94150D01*
X159400Y93317D01*
X160858Y92900D01*
X162317Y93108D01*
X163567Y93733D01*
X164400Y94566D01*
G01X176150Y92900D02*
Y105400D01*
G01X204233Y92900D02*
Y101233D01*
G01Y99567D02*
X205275Y100400D01*
X206317Y101025D01*
X207775Y101233D01*
X208817Y101025D01*
X210067Y100400D01*
G01X219525Y98525D02*
X226192D01*
X225567Y99983D01*
X224525Y100817D01*
X223067Y101233D01*
X221608Y101025D01*
X220358Y100400D01*
X219525Y98942D01*
X219108Y97691D01*
Y96442D01*
X219525Y95192D01*
X220567Y93941D01*
X221817Y93108D01*
X223275Y92900D01*
X224733Y93317D01*
X226192Y94566D01*
G01X238150Y92900D02*
Y105400D01*
G01X253650Y101233D02*
Y92900D01*
G01Y104566D02*
X253233Y104775D01*
Y105192D01*
X253650Y105400D01*
X254067Y105192D01*
Y104775D01*
X253650Y104566D01*
G01X266025Y98525D02*
X272692D01*
X272067Y99983D01*
X271025Y100817D01*
X269567Y101233D01*
X268108Y101025D01*
X266858Y100400D01*
X266025Y98942D01*
X265608Y97691D01*
Y96442D01*
X266025Y95192D01*
X267067Y93941D01*
X268317Y93108D01*
X269775Y92900D01*
X271233Y93317D01*
X272692Y94566D01*
G01X283400Y92900D02*
Y103525D01*
X283817Y104566D01*
X284650Y105192D01*
X285900Y105400D01*
X287150Y104983D01*
X287775Y103942D01*
G01X285275Y100400D02*
X281108D01*
G01X318983Y100192D02*
X317525Y101025D01*
X316275Y101233D01*
X314608Y100817D01*
X313358Y99983D01*
X312525Y98525D01*
X312316Y97067D01*
X312525Y95608D01*
X313358Y94358D01*
X314608Y93317D01*
X316275Y92900D01*
X317733Y93317D01*
X318983Y94150D01*
G01X331150Y92900D02*
X329900Y93108D01*
X328650Y93941D01*
X327816Y95400D01*
X327400Y97067D01*
X327816Y98733D01*
X328650Y100192D01*
X329900Y101025D01*
X331150Y101233D01*
X332400Y101025D01*
X333650Y100192D01*
X334483Y98733D01*
X334692Y97067D01*
X334483Y95400D01*
X333650Y93941D01*
X332400Y93108D01*
X331150Y92900D01*
G01X343108D02*
Y101233D01*
G01Y99150D02*
X343942Y100192D01*
X345192Y101025D01*
X346858Y101233D01*
X348317Y101025D01*
X349567Y100192D01*
X350192Y98733D01*
Y92900D01*
G01X358608D02*
Y101233D01*
G01Y99150D02*
X359442Y100192D01*
X360692Y101025D01*
X362358Y101233D01*
X363817Y101025D01*
X365067Y100192D01*
X365692Y98733D01*
Y92900D01*
G01X374525Y98525D02*
X381192D01*
X380567Y99983D01*
X379525Y100817D01*
X378067Y101233D01*
X376608Y101025D01*
X375358Y100400D01*
X374525Y98942D01*
X374108Y97691D01*
Y96442D01*
X374525Y95192D01*
X375567Y93941D01*
X376817Y93108D01*
X378275Y92900D01*
X379733Y93317D01*
X381192Y94566D01*
G01X396483Y100192D02*
X395025Y101025D01*
X393775Y101233D01*
X392108Y100817D01*
X390858Y99983D01*
X390025Y98525D01*
X389816Y97067D01*
X390025Y95608D01*
X390858Y94358D01*
X392108Y93317D01*
X393775Y92900D01*
X395233Y93317D01*
X396483Y94150D01*
G01X408650Y105400D02*
Y92900D01*
G01X405733Y101233D02*
X411567D01*
G01X642167Y-335717D02*
X651333Y-326550D01*
G01X646750Y-324883D02*
Y-337383D01*
G01X651333Y-335717D02*
X642167Y-326550D01*
G01X640500Y-331133D02*
X653000D01*
G01X657667Y-335717D02*
X666833Y-326550D01*
G01X662250Y-324883D02*
Y-337383D01*
G01X666833Y-335717D02*
X657667Y-326550D01*
G01X656000Y-331133D02*
X668500D01*
G01X673167Y-335717D02*
X682333Y-326550D01*
G01X677750Y-324883D02*
Y-337383D01*
G01X682333Y-335717D02*
X673167Y-326550D01*
G01X671500Y-331133D02*
X684000D01*
G01X688667Y-335717D02*
X697833Y-326550D01*
G01X693250Y-324883D02*
Y-337383D01*
G01X697833Y-335717D02*
X688667Y-326550D01*
G01X687000Y-331133D02*
X699500D01*
G01X708750Y-335717D02*
X708333Y-335508D01*
Y-335092D01*
X708750Y-334883D01*
X709167Y-335092D01*
Y-335508D01*
X708750Y-335717D01*
G01Y-330092D02*
X708333Y-329883D01*
Y-329467D01*
X708750Y-329258D01*
X709167Y-329467D01*
Y-329883D01*
X708750Y-330092D01*
G01X737250Y-322800D02*
X742250D01*
G01X739750D02*
Y-335300D01*
G01X737250D02*
X742250D01*
G01X752333Y-338425D02*
X753792Y-339258D01*
X755458Y-339467D01*
X756917Y-339258D01*
X758167Y-338217D01*
X759000Y-336758D01*
Y-326967D01*
G01Y-328633D02*
X758167Y-327800D01*
X756917Y-327175D01*
X755458Y-326967D01*
X753792Y-327383D01*
X752750Y-328217D01*
X751916Y-329675D01*
X751500Y-331133D01*
X751708Y-332384D01*
X752542Y-333842D01*
X753792Y-334883D01*
X755458Y-335300D01*
X756708Y-335092D01*
X758167Y-334259D01*
X759000Y-333425D01*
G01X767208Y-335300D02*
Y-326967D01*
G01Y-329050D02*
X768042Y-328008D01*
X769292Y-327175D01*
X770958Y-326967D01*
X772417Y-327175D01*
X773667Y-328008D01*
X774292Y-329467D01*
Y-335300D01*
G01X786250D02*
X785000Y-335092D01*
X783750Y-334259D01*
X782916Y-332800D01*
X782500Y-331133D01*
X782916Y-329467D01*
X783750Y-328008D01*
X785000Y-327175D01*
X786250Y-326967D01*
X787500Y-327175D01*
X788750Y-328008D01*
X789583Y-329467D01*
X789792Y-331133D01*
X789583Y-332800D01*
X788750Y-334259D01*
X787500Y-335092D01*
X786250Y-335300D01*
G01X798833D02*
Y-326967D01*
G01Y-328633D02*
X799875Y-327800D01*
X800917Y-327175D01*
X802375Y-326967D01*
X803417Y-327175D01*
X804667Y-327800D01*
G01X814125Y-329675D02*
X820792D01*
X820167Y-328217D01*
X819125Y-327383D01*
X817667Y-326967D01*
X816208Y-327175D01*
X814958Y-327800D01*
X814125Y-329258D01*
X813708Y-330509D01*
Y-331758D01*
X814125Y-333008D01*
X815167Y-334259D01*
X816417Y-335092D01*
X817875Y-335300D01*
X819333Y-334883D01*
X820792Y-333634D01*
G01X848250Y-335300D02*
Y-322800D01*
X845750Y-325300D01*
G01Y-335300D02*
X850750D01*
G01X873000D02*
Y-326967D01*
G01Y-329258D02*
X873625Y-328217D01*
X874667Y-327383D01*
X876125Y-326967D01*
X877583Y-327383D01*
X878625Y-328217D01*
X879250Y-329258D01*
Y-335300D01*
G01Y-329258D02*
X879875Y-328217D01*
X880917Y-327383D01*
X882375Y-326967D01*
X883833Y-327383D01*
X884875Y-328217D01*
X885500Y-329467D01*
Y-335300D01*
G01X894750Y-326967D02*
Y-335300D01*
G01Y-323634D02*
X894333Y-323425D01*
Y-323008D01*
X894750Y-322800D01*
X895167Y-323008D01*
Y-323425D01*
X894750Y-323634D01*
G01X910250Y-335300D02*
Y-322800D01*
G01X936667Y-335300D02*
Y-322800D01*
X940833D01*
X942500Y-323425D01*
X943750Y-324258D01*
X944792Y-325508D01*
X945625Y-326967D01*
X945833Y-329050D01*
X945625Y-331133D01*
X944792Y-332592D01*
X943750Y-333842D01*
X942500Y-334675D01*
X940833Y-335300D01*
X936667D01*
G01X954042Y-331133D02*
X959458D01*
G01X976833Y-323842D02*
X975583Y-323217D01*
X974125Y-322800D01*
X972458D01*
X970583Y-323425D01*
X969125Y-324467D01*
X968083Y-325717D01*
X967250Y-327800D01*
X967041Y-329675D01*
X967458Y-331550D01*
X968083Y-332800D01*
X969333Y-334050D01*
X970792Y-334883D01*
X972250Y-335300D01*
X973708D01*
X975167Y-334883D01*
X976417Y-334259D01*
X977459Y-333425D01*
G01X987750Y-335300D02*
X986083Y-335092D01*
X984625Y-334259D01*
X983375Y-333008D01*
X982541Y-331550D01*
X982125Y-329883D01*
Y-328217D01*
X982541Y-326550D01*
X983375Y-325092D01*
X984625Y-323842D01*
X986083Y-323008D01*
X987750Y-322800D01*
X989417Y-323008D01*
X990875Y-323842D01*
X992125Y-325092D01*
X992959Y-326550D01*
X993375Y-328217D01*
Y-329883D01*
X992959Y-331550D01*
X992125Y-333008D01*
X990875Y-334259D01*
X989417Y-335092D01*
X987750Y-335300D01*
G01X998667D02*
Y-322800D01*
X1002833D01*
X1004500Y-323425D01*
X1005750Y-324258D01*
X1006792Y-325508D01*
X1007625Y-326967D01*
X1007833Y-329050D01*
X1007625Y-331133D01*
X1006792Y-332592D01*
X1005750Y-333842D01*
X1004500Y-334675D01*
X1002833Y-335300D01*
X998667D01*
G01X1022917D02*
X1014583D01*
Y-322800D01*
X1022917D01*
G01X1019583Y-328842D02*
X1014583D01*
G01X646358Y-290400D02*
Y-277900D01*
X655942Y-290400D01*
Y-277900D01*
G01X666650Y-290400D02*
X665400Y-290192D01*
X664150Y-289359D01*
X663316Y-287900D01*
X662900Y-286233D01*
X663316Y-284567D01*
X664150Y-283108D01*
X665400Y-282275D01*
X666650Y-282067D01*
X667900Y-282275D01*
X669150Y-283108D01*
X669983Y-284567D01*
X670192Y-286233D01*
X669983Y-287900D01*
X669150Y-289359D01*
X667900Y-290192D01*
X666650Y-290400D01*
G01X682150Y-277900D02*
Y-290400D01*
G01X679233Y-282067D02*
X685067D01*
G01X694525Y-284775D02*
X701192D01*
X700567Y-283317D01*
X699525Y-282483D01*
X698067Y-282067D01*
X696608Y-282275D01*
X695358Y-282900D01*
X694525Y-284358D01*
X694108Y-285609D01*
Y-286858D01*
X694525Y-288108D01*
X695567Y-289359D01*
X696817Y-290192D01*
X698275Y-290400D01*
X699733Y-289983D01*
X701192Y-288734D01*
G01X710025Y-288942D02*
X711067Y-289775D01*
X712525Y-290400D01*
X713775D01*
X715025Y-289983D01*
X715858Y-289359D01*
X716275Y-288525D01*
X716067Y-287275D01*
X715233Y-286650D01*
X711483Y-285400D01*
X710650Y-283942D01*
X711067Y-282900D01*
X711900Y-282275D01*
X713150Y-282067D01*
X714400Y-282275D01*
X715650Y-282900D01*
G01X728650Y-290817D02*
X728233Y-290608D01*
Y-290192D01*
X728650Y-289983D01*
X729067Y-290192D01*
Y-290608D01*
X728650Y-290817D01*
G01Y-285192D02*
X728233Y-284983D01*
Y-284567D01*
X728650Y-284358D01*
X729067Y-284567D01*
Y-284983D01*
X728650Y-285192D01*
G54D11*
G01X-25267Y-107100D02*
X-31933D01*
Y-97100D01*
X-25267D01*
G01X-27933Y-101933D02*
X-31933D01*
G01X-20800Y-107100D02*
X-13800Y-97100D01*
G01X-20800D02*
X-13800Y-107100D01*
G01X-6000Y-107433D02*
X-6333Y-107267D01*
Y-106933D01*
X-6000Y-106767D01*
X-5667Y-106933D01*
Y-107267D01*
X-6000Y-107433D01*
G01Y-102934D02*
X-6333Y-102767D01*
Y-102433D01*
X-6000Y-102267D01*
X-5667Y-102433D01*
Y-102767D01*
X-6000Y-102934D01*
G01X13433Y-107100D02*
Y-97100D01*
X19767D01*
G01X17433Y-101933D02*
X13433D01*
G01X24567Y-97100D02*
Y-107100D01*
X31233D01*
G01X35033D02*
X39200Y-97100D01*
X43367Y-107100D01*
G01X41867Y-103600D02*
X36533D01*
G01X47000Y-105767D02*
X48333Y-106600D01*
X49833Y-107100D01*
X51167D01*
X52500Y-106600D01*
X53500Y-105767D01*
X54000Y-104600D01*
X53667Y-103434D01*
X52833Y-102433D01*
X51333Y-101767D01*
X49333Y-101433D01*
X48167Y-100767D01*
X47667Y-99600D01*
X48000Y-98433D01*
X48833Y-97600D01*
X50000Y-97100D01*
X51167D01*
X52333Y-97433D01*
X53333Y-98267D01*
G01X58300Y-107100D02*
Y-97100D01*
G01X65300D02*
Y-107100D01*
G01Y-102100D02*
X58300D01*
G01X84400Y-97100D02*
Y-107100D01*
G01X80567Y-97100D02*
X88233D01*
G01X92367Y-107100D02*
Y-97100D01*
X96533D01*
X97867Y-97600D01*
X98700Y-98267D01*
X99033Y-99600D01*
X98700Y-100933D01*
X97700Y-101767D01*
X96533Y-102267D01*
X92367D01*
G01X96533D02*
X99033Y-107100D01*
G01X107000D02*
Y-97100D01*
X105000Y-99100D01*
G01Y-107100D02*
X109000D01*
G01X118300Y-97100D02*
X116966Y-97433D01*
X115967Y-98267D01*
X115300Y-99267D01*
X114800Y-100600D01*
X114633Y-102100D01*
X114800Y-103600D01*
X115300Y-104933D01*
X115967Y-105934D01*
X116966Y-106767D01*
X118300Y-107100D01*
X119633Y-106767D01*
X120633Y-105934D01*
X121300Y-104933D01*
X121800Y-103600D01*
X121967Y-102100D01*
X121800Y-100600D01*
X121300Y-99267D01*
X120633Y-98267D01*
X119633Y-97433D01*
X118300Y-97100D01*
G01X125933Y-105100D02*
X126933Y-106267D01*
X128266Y-106933D01*
X129767Y-107100D01*
X131100Y-106933D01*
X132433Y-106100D01*
X133267Y-105100D01*
X133433Y-104100D01*
X133100Y-102934D01*
X131933Y-102100D01*
X130767Y-101767D01*
X129267D01*
G01X130767D02*
X131767Y-101267D01*
X132600Y-100434D01*
X132933Y-99433D01*
X132600Y-98433D01*
X131767Y-97600D01*
X130267Y-97100D01*
X128767Y-97267D01*
X127267Y-97933D01*
G01X135900Y-110433D02*
X145900D01*
G01X149367Y-105934D02*
X150533Y-106767D01*
X151867Y-107100D01*
X153200Y-106767D01*
X154367Y-105767D01*
X155200Y-104267D01*
X155533Y-102767D01*
Y-100933D01*
X155200Y-99433D01*
X154367Y-98100D01*
X153367Y-97433D01*
X152200Y-97100D01*
X150866Y-97433D01*
X149867Y-98100D01*
X149200Y-99100D01*
X148867Y-100434D01*
X149200Y-101600D01*
X150033Y-102767D01*
X151033Y-103434D01*
X152200Y-103600D01*
X153533Y-103267D01*
X154533Y-102433D01*
X155533Y-100933D01*
G01X159833Y-105100D02*
X160833Y-106267D01*
X162166Y-106933D01*
X163667Y-107100D01*
X165000Y-106933D01*
X166333Y-106100D01*
X167167Y-105100D01*
X167333Y-104100D01*
X167000Y-102934D01*
X165833Y-102100D01*
X164667Y-101767D01*
X163167D01*
G01X164667D02*
X165667Y-101267D01*
X166500Y-100434D01*
X166833Y-99433D01*
X166500Y-98433D01*
X165667Y-97600D01*
X164167Y-97100D01*
X162667Y-97267D01*
X161167Y-97933D01*
G01X169800Y-110433D02*
X179800D01*
G01X182433Y-105100D02*
X183433Y-106267D01*
X184766Y-106933D01*
X186267Y-107100D01*
X187600Y-106933D01*
X188933Y-106100D01*
X189767Y-105100D01*
X189933Y-104100D01*
X189600Y-102934D01*
X188433Y-102100D01*
X187267Y-101767D01*
X185767D01*
G01X187267D02*
X188267Y-101267D01*
X189100Y-100434D01*
X189433Y-99433D01*
X189100Y-98433D01*
X188267Y-97600D01*
X186767Y-97100D01*
X185267Y-97267D01*
X183767Y-97933D01*
G01X197400Y-97100D02*
X196066Y-97433D01*
X195067Y-98267D01*
X194400Y-99267D01*
X193900Y-100600D01*
X193733Y-102100D01*
X193900Y-103600D01*
X194400Y-104933D01*
X195067Y-105934D01*
X196066Y-106767D01*
X197400Y-107100D01*
X198733Y-106767D01*
X199733Y-105934D01*
X200400Y-104933D01*
X200900Y-103600D01*
X201067Y-102100D01*
X200900Y-100600D01*
X200400Y-99267D01*
X199733Y-98267D01*
X198733Y-97433D01*
X197400Y-97100D01*
G01X208700Y-107433D02*
X208367Y-107267D01*
Y-106933D01*
X208700Y-106767D01*
X209033Y-106933D01*
Y-107267D01*
X208700Y-107433D01*
G01Y-102934D02*
X208367Y-102767D01*
Y-102433D01*
X208700Y-102267D01*
X209033Y-102433D01*
Y-102767D01*
X208700Y-102934D01*
G01X-18267Y34900D02*
X-17267Y33733D01*
X-15934Y33067D01*
X-14433Y32900D01*
X-13100Y33067D01*
X-11767Y33900D01*
X-10933Y34900D01*
X-10767Y35900D01*
X-11100Y37066D01*
X-12267Y37900D01*
X-13433Y38233D01*
X-14933D01*
G01X-13433D02*
X-12433Y38733D01*
X-11600Y39566D01*
X-11267Y40567D01*
X-11600Y41567D01*
X-12433Y42400D01*
X-13933Y42900D01*
X-15433Y42733D01*
X-16933Y42067D01*
G01X-3300Y32567D02*
X-3633Y32733D01*
Y33067D01*
X-3300Y33233D01*
X-2967Y33067D01*
Y32733D01*
X-3300Y32567D01*
G01X-17767Y57233D02*
X-16767Y58233D01*
X-15600Y58733D01*
X-14267Y58900D01*
X-12600Y58567D01*
X-11433Y57733D01*
X-11100Y56733D01*
X-11267Y55733D01*
X-11933Y54900D01*
X-15267Y53233D01*
X-16767Y52067D01*
X-17767Y50400D01*
X-18100Y48900D01*
X-11100D01*
G01X-3300Y48567D02*
X-3633Y48733D01*
Y49067D01*
X-3300Y49233D01*
X-2967Y49067D01*
Y48733D01*
X-3300Y48567D01*
G01X-14600Y64900D02*
Y74900D01*
X-16600Y72900D01*
G01Y64900D02*
X-12600D01*
G01X-3300Y64567D02*
X-3633Y64733D01*
Y65067D01*
X-3300Y65233D01*
X-2967Y65067D01*
Y64733D01*
X-3300Y64567D01*
G01X16133Y64900D02*
Y74900D01*
X22467D01*
G01X20133Y70067D02*
X16133D01*
G01X27267Y74900D02*
Y64900D01*
X33933D01*
G01X37733D02*
X41900Y74900D01*
X46067Y64900D01*
G01X44567Y68400D02*
X39233D01*
G01X49700Y66233D02*
X51033Y65400D01*
X52533Y64900D01*
X53867D01*
X55200Y65400D01*
X56200Y66233D01*
X56700Y67400D01*
X56367Y68566D01*
X55533Y69567D01*
X54033Y70233D01*
X52033Y70567D01*
X50867Y71233D01*
X50367Y72400D01*
X50700Y73567D01*
X51533Y74400D01*
X52700Y74900D01*
X53867D01*
X55033Y74567D01*
X56033Y73733D01*
G01X61000Y64900D02*
Y74900D01*
G01X68000D02*
Y64900D01*
G01Y69900D02*
X61000D01*
G01X87100Y74900D02*
Y64900D01*
G01X83267Y74900D02*
X90933D01*
G01X94900Y64900D02*
Y74900D01*
G01X101900D02*
Y64900D01*
G01Y69900D02*
X94900D01*
G01X105367Y64900D02*
Y74900D01*
X109700Y66567D01*
X114033Y74900D01*
Y64900D01*
G01X117667Y74900D02*
Y64900D01*
X124333D01*
G01X132300D02*
Y74900D01*
X130300Y72900D01*
G01Y64900D02*
X134300D01*
G01X143600Y74900D02*
X142266Y74567D01*
X141267Y73733D01*
X140600Y72733D01*
X140100Y71400D01*
X139933Y69900D01*
X140100Y68400D01*
X140600Y67067D01*
X141267Y66066D01*
X142266Y65233D01*
X143600Y64900D01*
X144933Y65233D01*
X145933Y66066D01*
X146600Y67067D01*
X147100Y68400D01*
X147267Y69900D01*
X147100Y71400D01*
X146600Y72733D01*
X145933Y73733D01*
X144933Y74567D01*
X143600Y74900D01*
G01X166200Y64567D02*
X165867Y64733D01*
Y65067D01*
X166200Y65233D01*
X166533Y65067D01*
Y64733D01*
X166200Y64567D01*
G01Y69066D02*
X165867Y69233D01*
Y69567D01*
X166200Y69733D01*
X166533Y69567D01*
Y69233D01*
X166200Y69066D01*
G01X185633Y64900D02*
Y74900D01*
X191967D01*
G01X189633Y70067D02*
X185633D01*
G01X197267Y71566D02*
Y66900D01*
X197933Y65733D01*
X198933Y65067D01*
X200100Y64900D01*
X201267Y65067D01*
X202267Y65733D01*
X202933Y66900D01*
G01Y64900D02*
Y71566D01*
G01X211400Y64900D02*
Y74900D01*
G01X222700Y64900D02*
Y74900D01*
G01X247967Y70733D02*
X246800Y71400D01*
X245800Y71566D01*
X244467Y71233D01*
X243467Y70567D01*
X242800Y69400D01*
X242633Y68233D01*
X242800Y67067D01*
X243467Y66066D01*
X244467Y65233D01*
X245800Y64900D01*
X246967Y65233D01*
X247967Y65900D01*
G01X256600Y64900D02*
X255600Y65067D01*
X254600Y65733D01*
X253933Y66900D01*
X253600Y68233D01*
X253933Y69567D01*
X254600Y70733D01*
X255600Y71400D01*
X256600Y71566D01*
X257600Y71400D01*
X258600Y70733D01*
X259267Y69567D01*
X259433Y68233D01*
X259267Y66900D01*
X258600Y65733D01*
X257600Y65067D01*
X256600Y64900D01*
G01X265067D02*
Y71566D01*
G01Y69900D02*
X265733Y70733D01*
X266733Y71400D01*
X268067Y71566D01*
X269233Y71400D01*
X270233Y70733D01*
X270733Y69567D01*
Y64900D01*
G01X279200Y74900D02*
Y64900D01*
G01X276867Y71566D02*
X281533D01*
G01X293500Y64900D02*
Y71566D01*
G01Y70400D02*
X292833Y71067D01*
X291833Y71400D01*
X290667Y71566D01*
X289500Y71233D01*
X288500Y70567D01*
X287833Y69567D01*
X287500Y68233D01*
X287833Y66900D01*
X288500Y65900D01*
X289500Y65233D01*
X290667Y64900D01*
X291833Y65067D01*
X292833Y65567D01*
X293500Y66233D01*
G01X304467Y70733D02*
X303300Y71400D01*
X302300Y71566D01*
X300967Y71233D01*
X299967Y70567D01*
X299300Y69400D01*
X299133Y68233D01*
X299300Y67067D01*
X299967Y66066D01*
X300967Y65233D01*
X302300Y64900D01*
X303467Y65233D01*
X304467Y65900D01*
G01X313100Y74900D02*
Y64900D01*
G01X310767Y71566D02*
X315433D01*
G01X47733Y-601800D02*
X41067D01*
Y-591800D01*
X47733D01*
G01X45067Y-596633D02*
X41067D01*
G01X55700Y-602133D02*
X55367Y-601967D01*
Y-601633D01*
X55700Y-601467D01*
X56033Y-601633D01*
Y-601967D01*
X55700Y-602133D01*
G01Y-597634D02*
X55367Y-597467D01*
Y-597133D01*
X55700Y-596967D01*
X56033Y-597133D01*
Y-597467D01*
X55700Y-597634D01*
G01X31033Y-627800D02*
X24367D01*
Y-617800D01*
X31033D01*
G01X28367Y-622633D02*
X24367D01*
G01X35500Y-627800D02*
X42500Y-617800D01*
G01X35500D02*
X42500Y-627800D01*
G01X50300Y-628133D02*
X49967Y-627967D01*
Y-627633D01*
X50300Y-627467D01*
X50633Y-627633D01*
Y-627967D01*
X50300Y-628133D01*
G01Y-623634D02*
X49967Y-623467D01*
Y-623133D01*
X50300Y-622967D01*
X50633Y-623133D01*
Y-623467D01*
X50300Y-623634D01*
G01X69733Y-627800D02*
Y-617800D01*
X76067D01*
G01X73733Y-622633D02*
X69733D01*
G01X80867Y-617800D02*
Y-627800D01*
X87533D01*
G01X91333D02*
X95500Y-617800D01*
X99667Y-627800D01*
G01X98167Y-624300D02*
X92833D01*
G01X103300Y-626467D02*
X104633Y-627300D01*
X106133Y-627800D01*
X107467D01*
X108800Y-627300D01*
X109800Y-626467D01*
X110300Y-625300D01*
X109967Y-624134D01*
X109133Y-623133D01*
X107633Y-622467D01*
X105633Y-622133D01*
X104467Y-621467D01*
X103967Y-620300D01*
X104300Y-619133D01*
X105133Y-618300D01*
X106300Y-617800D01*
X107467D01*
X108633Y-618133D01*
X109633Y-618967D01*
G01X114600Y-627800D02*
Y-617800D01*
G01X121600D02*
Y-627800D01*
G01Y-622800D02*
X114600D01*
G01X140700Y-617800D02*
Y-627800D01*
G01X136867Y-617800D02*
X144533D01*
G01X148667Y-627800D02*
Y-617800D01*
X152833D01*
X154167Y-618300D01*
X155000Y-618967D01*
X155333Y-620300D01*
X155000Y-621633D01*
X154000Y-622467D01*
X152833Y-622967D01*
X148667D01*
G01X152833D02*
X155333Y-627800D01*
G01X160133Y-623634D02*
X161300Y-622467D01*
X162300Y-621800D01*
X163633Y-621467D01*
X164800Y-621800D01*
X165633Y-622467D01*
X166300Y-623467D01*
X166467Y-624633D01*
X166300Y-625633D01*
X165633Y-626634D01*
X164633Y-627467D01*
X163467Y-627800D01*
X162133Y-627467D01*
X160967Y-626467D01*
X160300Y-624967D01*
X160133Y-623300D01*
X160467Y-621134D01*
X160967Y-619967D01*
X161800Y-618800D01*
X162967Y-617967D01*
X164133Y-617800D01*
X165300Y-618133D01*
X166133Y-618967D01*
G01X174600Y-617800D02*
X173266Y-618133D01*
X172267Y-618967D01*
X171600Y-619967D01*
X171100Y-621300D01*
X170933Y-622800D01*
X171100Y-624300D01*
X171600Y-625633D01*
X172267Y-626634D01*
X173266Y-627467D01*
X174600Y-627800D01*
X175933Y-627467D01*
X176933Y-626634D01*
X177600Y-625633D01*
X178100Y-624300D01*
X178267Y-622800D01*
X178100Y-621300D01*
X177600Y-619967D01*
X176933Y-618967D01*
X175933Y-618133D01*
X174600Y-617800D01*
G01X182400Y-627800D02*
X189400Y-617800D01*
G01X182400D02*
X189400Y-627800D01*
G01X197200D02*
Y-617800D01*
X195200Y-619800D01*
G01Y-627800D02*
X199200D01*
G01X208500D02*
Y-617800D01*
X206500Y-619800D01*
G01Y-627800D02*
X210500D01*
G01X216967Y-626634D02*
X218133Y-627467D01*
X219467Y-627800D01*
X220800Y-627467D01*
X221967Y-626467D01*
X222800Y-624967D01*
X223133Y-623467D01*
Y-621633D01*
X222800Y-620133D01*
X221967Y-618800D01*
X220967Y-618133D01*
X219800Y-617800D01*
X218466Y-618133D01*
X217467Y-618800D01*
X216800Y-619800D01*
X216467Y-621134D01*
X216800Y-622300D01*
X217633Y-623467D01*
X218633Y-624134D01*
X219800Y-624300D01*
X221133Y-623967D01*
X222133Y-623133D01*
X223133Y-621633D01*
G01X226100Y-631133D02*
X236100D01*
G01X239233Y-619467D02*
X240233Y-618467D01*
X241400Y-617967D01*
X242733Y-617800D01*
X244400Y-618133D01*
X245567Y-618967D01*
X245900Y-619967D01*
X245733Y-620967D01*
X245067Y-621800D01*
X241733Y-623467D01*
X240233Y-624633D01*
X239233Y-626300D01*
X238900Y-627800D01*
X245900D01*
G01X253700Y-617800D02*
X252366Y-618133D01*
X251367Y-618967D01*
X250700Y-619967D01*
X250200Y-621300D01*
X250033Y-622800D01*
X250200Y-624300D01*
X250700Y-625633D01*
X251367Y-626634D01*
X252366Y-627467D01*
X253700Y-627800D01*
X255033Y-627467D01*
X256033Y-626634D01*
X256700Y-625633D01*
X257200Y-624300D01*
X257367Y-622800D01*
X257200Y-621300D01*
X256700Y-619967D01*
X256033Y-618967D01*
X255033Y-618133D01*
X253700Y-617800D01*
G01X261500Y-627800D02*
X268500Y-617800D01*
G01X261500D02*
X268500Y-627800D01*
G01X272633Y-625800D02*
X273633Y-626967D01*
X274966Y-627633D01*
X276467Y-627800D01*
X277800Y-627633D01*
X279133Y-626800D01*
X279967Y-625800D01*
X280133Y-624800D01*
X279800Y-623634D01*
X278633Y-622800D01*
X277467Y-622467D01*
X275967D01*
G01X277467D02*
X278467Y-621967D01*
X279300Y-621134D01*
X279633Y-620133D01*
X279300Y-619133D01*
X278467Y-618300D01*
X276967Y-617800D01*
X275467Y-617967D01*
X273967Y-618633D01*
G01X287600Y-617800D02*
X286266Y-618133D01*
X285267Y-618967D01*
X284600Y-619967D01*
X284100Y-621300D01*
X283933Y-622800D01*
X284100Y-624300D01*
X284600Y-625633D01*
X285267Y-626634D01*
X286266Y-627467D01*
X287600Y-627800D01*
X288933Y-627467D01*
X289933Y-626634D01*
X290600Y-625633D01*
X291100Y-624300D01*
X291267Y-622800D01*
X291100Y-621300D01*
X290600Y-619967D01*
X289933Y-618967D01*
X288933Y-618133D01*
X287600Y-617800D01*
G01X20667Y-578000D02*
Y-568000D01*
X28333Y-578000D01*
Y-568000D01*
G01X31633Y-578000D02*
X35800Y-568000D01*
X39967Y-578000D01*
G01X38467Y-574500D02*
X33133D01*
G01X42767Y-578000D02*
Y-568000D01*
X47100Y-576333D01*
X51433Y-568000D01*
Y-578000D01*
G01X61733D02*
X55067D01*
Y-568000D01*
X61733D01*
G01X59067Y-572833D02*
X55067D01*
G01X69700Y-578333D02*
X69367Y-578167D01*
Y-577833D01*
X69700Y-577667D01*
X70033Y-577833D01*
Y-578167D01*
X69700Y-578333D01*
G01Y-573834D02*
X69367Y-573667D01*
Y-573333D01*
X69700Y-573167D01*
X70033Y-573333D01*
Y-573667D01*
X69700Y-573834D01*
G01X92300Y-568000D02*
Y-578000D01*
G01X88467Y-568000D02*
X96133D01*
G01X100267Y-578000D02*
Y-568000D01*
X104433D01*
X105767Y-568500D01*
X106600Y-569167D01*
X106933Y-570500D01*
X106600Y-571833D01*
X105600Y-572667D01*
X104433Y-573167D01*
X100267D01*
G01X104433D02*
X106933Y-578000D01*
G01X110733D02*
X114900Y-568000D01*
X119067Y-578000D01*
G01X117567Y-574500D02*
X112233D01*
G01X122700Y-578000D02*
X129700Y-568000D01*
G01X122700D02*
X129700Y-578000D01*
G01X138833Y-572667D02*
X139500Y-572167D01*
X140000Y-571334D01*
X140333Y-570167D01*
X140000Y-569167D01*
X139333Y-568500D01*
X138167Y-568000D01*
X133667D01*
Y-578000D01*
X139167D01*
X140333Y-577333D01*
X141000Y-576333D01*
X141333Y-575167D01*
X141000Y-574000D01*
X140000Y-573000D01*
X138833Y-572667D01*
X133667D01*
G01X143800Y-581333D02*
X153800D01*
G01X163767Y-568833D02*
X162767Y-568333D01*
X161600Y-568000D01*
X160267D01*
X158766Y-568500D01*
X157600Y-569333D01*
X156767Y-570333D01*
X156100Y-572000D01*
X155933Y-573500D01*
X156267Y-575000D01*
X156767Y-576000D01*
X157767Y-577000D01*
X158933Y-577667D01*
X160100Y-578000D01*
X161267D01*
X162433Y-577667D01*
X163433Y-577167D01*
X164267Y-576500D01*
G01X167900Y-578000D02*
X174900Y-568000D01*
G01X167900D02*
X174900Y-578000D01*
G01X179033D02*
Y-568000D01*
X182367D01*
X183700Y-568500D01*
X184700Y-569167D01*
X185533Y-570167D01*
X186200Y-571334D01*
X186367Y-573000D01*
X186200Y-574667D01*
X185533Y-575833D01*
X184700Y-576834D01*
X183700Y-577500D01*
X182367Y-578000D01*
X179033D01*
G01X60233Y-512400D02*
X53567D01*
Y-502400D01*
X60233D01*
G01X57567Y-507233D02*
X53567D01*
G01X46933Y-433400D02*
Y-423400D01*
X50267D01*
X51600Y-423900D01*
X52600Y-424567D01*
X53433Y-425567D01*
X54100Y-426734D01*
X54267Y-428400D01*
X54100Y-430067D01*
X53433Y-431233D01*
X52600Y-432234D01*
X51600Y-432900D01*
X50267Y-433400D01*
X46933D01*
G01X58633Y-311800D02*
X51967D01*
Y-301800D01*
X58633D01*
G01X55967Y-306633D02*
X51967D01*
G01X63267Y-301800D02*
Y-311800D01*
X69933D01*
G01X74567Y-301800D02*
Y-311800D01*
X81233D01*
G01X87200Y-301800D02*
X91200D01*
G01X89200D02*
Y-311800D01*
G01X87200D02*
X91200D01*
G01X97167D02*
Y-301800D01*
X101167D01*
X102500Y-302300D01*
X103500Y-303467D01*
X103833Y-304800D01*
X103500Y-306133D01*
X102667Y-307133D01*
X101167Y-307634D01*
X97167D01*
G01X108300Y-310467D02*
X109633Y-311300D01*
X111133Y-311800D01*
X112467D01*
X113800Y-311300D01*
X114800Y-310467D01*
X115300Y-309300D01*
X114967Y-308134D01*
X114133Y-307133D01*
X112633Y-306467D01*
X110633Y-306133D01*
X109467Y-305467D01*
X108967Y-304300D01*
X109300Y-303133D01*
X110133Y-302300D01*
X111300Y-301800D01*
X112467D01*
X113633Y-302133D01*
X114633Y-302967D01*
G01X126433Y-311800D02*
X119767D01*
Y-301800D01*
X126433D01*
G01X123767Y-306633D02*
X119767D01*
G01X145700Y-301800D02*
Y-311800D01*
G01X141867Y-301800D02*
X149533D01*
G01X154167Y-311800D02*
Y-301800D01*
G01Y-306633D02*
X155000Y-305800D01*
X155833Y-305300D01*
X157167Y-305134D01*
X158167Y-305300D01*
X159333Y-305967D01*
X159833Y-306967D01*
Y-311800D01*
G01X165800Y-307300D02*
X171133D01*
X170633Y-306133D01*
X169800Y-305467D01*
X168633Y-305134D01*
X167467Y-305300D01*
X166467Y-305800D01*
X165800Y-306967D01*
X165467Y-307967D01*
Y-308967D01*
X165800Y-309967D01*
X166633Y-310967D01*
X167633Y-311633D01*
X168800Y-311800D01*
X169967Y-311467D01*
X171133Y-310467D01*
G01X177267Y-311800D02*
Y-305134D01*
G01Y-306467D02*
X178100Y-305800D01*
X178933Y-305300D01*
X180100Y-305134D01*
X180933Y-305300D01*
X181933Y-305800D01*
G01X185900Y-311800D02*
Y-305134D01*
G01Y-306967D02*
X186400Y-306133D01*
X187233Y-305467D01*
X188400Y-305134D01*
X189566Y-305467D01*
X190400Y-306133D01*
X190900Y-306967D01*
Y-311800D01*
G01Y-306967D02*
X191400Y-306133D01*
X192233Y-305467D01*
X193400Y-305134D01*
X194567Y-305467D01*
X195400Y-306133D01*
X195900Y-307133D01*
Y-311800D01*
G01X205200D02*
Y-305134D01*
G01Y-306300D02*
X204533Y-305633D01*
X203533Y-305300D01*
X202367Y-305134D01*
X201200Y-305467D01*
X200200Y-306133D01*
X199533Y-307133D01*
X199200Y-308467D01*
X199533Y-309800D01*
X200200Y-310800D01*
X201200Y-311467D01*
X202367Y-311800D01*
X203533Y-311633D01*
X204533Y-311133D01*
X205200Y-310467D01*
G01X213500Y-311800D02*
Y-301800D01*
G01X57100Y-69900D02*
X61100D01*
G01X59100D02*
Y-79900D01*
G01X57100D02*
X61100D01*
G01X67567D02*
Y-73234D01*
G01Y-74900D02*
X68233Y-74067D01*
X69233Y-73400D01*
X70567Y-73234D01*
X71733Y-73400D01*
X72733Y-74067D01*
X73233Y-75233D01*
Y-79900D01*
G01X78867D02*
Y-73234D01*
G01Y-74900D02*
X79533Y-74067D01*
X80533Y-73400D01*
X81867Y-73234D01*
X83033Y-73400D01*
X84033Y-74067D01*
X84533Y-75233D01*
Y-79900D01*
G01X90500Y-75400D02*
X95833D01*
X95333Y-74233D01*
X94500Y-73567D01*
X93333Y-73234D01*
X92167Y-73400D01*
X91167Y-73900D01*
X90500Y-75067D01*
X90167Y-76067D01*
Y-77067D01*
X90500Y-78067D01*
X91333Y-79067D01*
X92333Y-79733D01*
X93500Y-79900D01*
X94667Y-79567D01*
X95833Y-78567D01*
G01X101967Y-79900D02*
Y-73234D01*
G01Y-74567D02*
X102800Y-73900D01*
X103633Y-73400D01*
X104800Y-73234D01*
X105633Y-73400D01*
X106633Y-73900D01*
G01X123233Y-79900D02*
Y-69900D01*
X126567D01*
X127900Y-70400D01*
X128900Y-71067D01*
X129733Y-72067D01*
X130400Y-73234D01*
X130567Y-74900D01*
X130400Y-76567D01*
X129733Y-77733D01*
X128900Y-78734D01*
X127900Y-79400D01*
X126567Y-79900D01*
X123233D01*
G01X138200Y-73234D02*
Y-79900D01*
G01Y-70567D02*
X137867Y-70400D01*
Y-70067D01*
X138200Y-69900D01*
X138533Y-70067D01*
Y-70400D01*
X138200Y-70567D01*
G01X152500Y-79900D02*
Y-73234D01*
G01Y-74400D02*
X151833Y-73733D01*
X150833Y-73400D01*
X149667Y-73234D01*
X148500Y-73567D01*
X147500Y-74233D01*
X146833Y-75233D01*
X146500Y-76567D01*
X146833Y-77900D01*
X147500Y-78900D01*
X148500Y-79567D01*
X149667Y-79900D01*
X150833Y-79733D01*
X151833Y-79233D01*
X152500Y-78567D01*
G01X155800Y-79900D02*
Y-73234D01*
G01Y-75067D02*
X156300Y-74233D01*
X157133Y-73567D01*
X158300Y-73234D01*
X159466Y-73567D01*
X160300Y-74233D01*
X160800Y-75067D01*
Y-79900D01*
G01Y-75067D02*
X161300Y-74233D01*
X162133Y-73567D01*
X163300Y-73234D01*
X164467Y-73567D01*
X165300Y-74233D01*
X165800Y-75233D01*
Y-79900D01*
G01X169600Y-75400D02*
X174933D01*
X174433Y-74233D01*
X173600Y-73567D01*
X172433Y-73234D01*
X171267Y-73400D01*
X170267Y-73900D01*
X169600Y-75067D01*
X169267Y-76067D01*
Y-77067D01*
X169600Y-78067D01*
X170433Y-79067D01*
X171433Y-79733D01*
X172600Y-79900D01*
X173767Y-79567D01*
X174933Y-78567D01*
G01X183400Y-69900D02*
Y-79900D01*
G01X181067Y-73234D02*
X185733D01*
G01X192200Y-75400D02*
X197533D01*
X197033Y-74233D01*
X196200Y-73567D01*
X195033Y-73234D01*
X193867Y-73400D01*
X192867Y-73900D01*
X192200Y-75067D01*
X191867Y-76067D01*
Y-77067D01*
X192200Y-78067D01*
X193033Y-79067D01*
X194033Y-79733D01*
X195200Y-79900D01*
X196367Y-79567D01*
X197533Y-78567D01*
G01X203667Y-79900D02*
Y-73234D01*
G01Y-74567D02*
X204500Y-73900D01*
X205333Y-73400D01*
X206500Y-73234D01*
X207333Y-73400D01*
X208333Y-73900D01*
G01X14400Y56900D02*
X16733Y46900D01*
X19400Y56900D01*
X22067Y46900D01*
X24400Y56900D01*
G01X30700Y53566D02*
Y46900D01*
G01Y56233D02*
X30367Y56400D01*
Y56733D01*
X30700Y56900D01*
X31033Y56733D01*
Y56400D01*
X30700Y56233D01*
G01X39500Y48066D02*
X40333Y47400D01*
X41500Y46900D01*
X42500D01*
X43500Y47233D01*
X44167Y47733D01*
X44500Y48400D01*
X44333Y49400D01*
X43667Y49900D01*
X40666Y50900D01*
X40000Y52067D01*
X40333Y52900D01*
X41000Y53400D01*
X42000Y53566D01*
X43000Y53400D01*
X44000Y52900D01*
G01X53300Y56900D02*
Y46900D01*
G01X50967Y53566D02*
X55633D01*
G01X62267Y46900D02*
Y53566D01*
G01Y52233D02*
X63100Y52900D01*
X63933Y53400D01*
X65100Y53566D01*
X65933Y53400D01*
X66933Y52900D01*
G01X75900Y46900D02*
X74900Y47067D01*
X73900Y47733D01*
X73233Y48900D01*
X72900Y50233D01*
X73233Y51567D01*
X73900Y52733D01*
X74900Y53400D01*
X75900Y53566D01*
X76900Y53400D01*
X77900Y52733D01*
X78567Y51567D01*
X78733Y50233D01*
X78567Y48900D01*
X77900Y47733D01*
X76900Y47067D01*
X75900Y46900D01*
G01X84367D02*
Y53566D01*
G01Y51900D02*
X85033Y52733D01*
X86033Y53400D01*
X87367Y53566D01*
X88533Y53400D01*
X89533Y52733D01*
X90033Y51567D01*
Y46900D01*
G01X109800Y56900D02*
Y46900D01*
G01X105967Y56900D02*
X113633D01*
G01X117600Y46900D02*
Y56900D01*
G01X124600D02*
Y46900D01*
G01Y51900D02*
X117600D01*
G01X128067Y46900D02*
Y56900D01*
X132400Y48567D01*
X136733Y56900D01*
Y46900D01*
G01X140367Y56900D02*
Y46900D01*
X147033D01*
G01X169300Y56900D02*
Y46900D01*
G01Y48400D02*
X168633Y47567D01*
X167633Y47067D01*
X166467Y46900D01*
X165133Y47233D01*
X164133Y48066D01*
X163467Y49067D01*
X163300Y50233D01*
X163467Y51400D01*
X164133Y52400D01*
X165133Y53233D01*
X166467Y53566D01*
X167633Y53400D01*
X168467Y53067D01*
X169300Y52400D01*
G01X175100Y51400D02*
X180433D01*
X179933Y52567D01*
X179100Y53233D01*
X177933Y53566D01*
X176767Y53400D01*
X175767Y52900D01*
X175100Y51733D01*
X174767Y50733D01*
Y49733D01*
X175100Y48733D01*
X175933Y47733D01*
X176933Y47067D01*
X178100Y46900D01*
X179267Y47233D01*
X180433Y48233D01*
G01X187900Y46900D02*
Y55400D01*
X188233Y56233D01*
X188900Y56733D01*
X189900Y56900D01*
X190900Y56567D01*
X191400Y55733D01*
G01X189400Y52900D02*
X186067D01*
G01X203200Y46900D02*
Y53566D01*
G01Y52400D02*
X202533Y53067D01*
X201533Y53400D01*
X200367Y53566D01*
X199200Y53233D01*
X198200Y52567D01*
X197533Y51567D01*
X197200Y50233D01*
X197533Y48900D01*
X198200Y47900D01*
X199200Y47233D01*
X200367Y46900D01*
X201533Y47067D01*
X202533Y47567D01*
X203200Y48233D01*
G01X208667Y53566D02*
Y48900D01*
X209333Y47733D01*
X210333Y47067D01*
X211500Y46900D01*
X212667Y47067D01*
X213667Y47733D01*
X214333Y48900D01*
G01Y46900D02*
Y53566D01*
G01X222800Y46900D02*
Y56900D01*
G01X234100D02*
Y46900D01*
G01X231767Y53566D02*
X236433D01*
G01X256700Y56900D02*
Y46900D01*
G01X254367Y53566D02*
X259033D01*
G01X264500Y43900D02*
X265500Y43567D01*
X266833Y43900D01*
X267667Y44567D01*
X268333Y45400D01*
X269333Y48066D01*
X271500Y53566D01*
G01X266167D02*
X269333Y48066D01*
G01X276300Y43567D02*
Y53566D01*
G01Y52067D02*
X277133Y52900D01*
X277966Y53400D01*
X279300Y53566D01*
X280467Y53400D01*
X281633Y52567D01*
X282133Y51400D01*
X282300Y50233D01*
X282133Y49067D01*
X281633Y47900D01*
X280633Y47233D01*
X279300Y46900D01*
X278133Y47067D01*
X276967Y47567D01*
X276300Y48233D01*
G01X288100Y51400D02*
X293433D01*
X292933Y52567D01*
X292100Y53233D01*
X290933Y53566D01*
X289767Y53400D01*
X288767Y52900D01*
X288100Y51733D01*
X287767Y50733D01*
Y49733D01*
X288100Y48733D01*
X288933Y47733D01*
X289933Y47067D01*
X291100Y46900D01*
X292267Y47233D01*
X293433Y48233D01*
G01X95733Y-602100D02*
X89067D01*
Y-592100D01*
X95733D01*
G01X93067Y-596933D02*
X89067D01*
G01X101533Y-600267D02*
X105867D01*
G01Y-597267D02*
X101533D01*
G01X111333Y-600600D02*
X112333Y-601433D01*
X113500Y-601933D01*
X115000Y-602100D01*
X116500Y-601767D01*
X117667Y-601100D01*
X118500Y-599933D01*
X118667Y-598600D01*
X118333Y-597267D01*
X117500Y-596433D01*
X116333Y-595767D01*
X115167Y-595600D01*
X114000Y-595767D01*
X112500Y-596433D01*
X113000Y-592100D01*
X117500D01*
G01X133267Y-602100D02*
Y-592100D01*
X137600Y-600433D01*
X141933Y-592100D01*
Y-602100D01*
G01X146900Y-592100D02*
X150900D01*
G01X148900D02*
Y-602100D01*
G01X146900D02*
X150900D01*
G01X156867Y-592100D02*
Y-602100D01*
X163533D01*
G01X168000Y-600767D02*
X169333Y-601600D01*
X170833Y-602100D01*
X172167D01*
X173500Y-601600D01*
X174500Y-600767D01*
X175000Y-599600D01*
X174667Y-598434D01*
X173833Y-597433D01*
X172333Y-596767D01*
X170333Y-596433D01*
X169167Y-595767D01*
X168667Y-594600D01*
X169000Y-593433D01*
X169833Y-592600D01*
X171000Y-592100D01*
X172167D01*
X173333Y-592433D01*
X174333Y-593267D01*
G01X193267Y-605433D02*
X191600Y-603767D01*
X190767Y-602100D01*
Y-595434D01*
X191600Y-593767D01*
X193267Y-592100D01*
G01X208400Y-602100D02*
Y-595434D01*
G01Y-596600D02*
X207733Y-595933D01*
X206733Y-595600D01*
X205567Y-595434D01*
X204400Y-595767D01*
X203400Y-596433D01*
X202733Y-597433D01*
X202400Y-598767D01*
X202733Y-600100D01*
X203400Y-601100D01*
X204400Y-601767D01*
X205567Y-602100D01*
X206733Y-601933D01*
X207733Y-601433D01*
X208400Y-600767D01*
G01X216700Y-602100D02*
Y-592100D01*
G01X223833Y-595434D02*
X225833Y-602100D01*
X228000Y-595434D01*
X230167Y-602100D01*
X232167Y-595434D01*
G01X242300Y-602100D02*
Y-595434D01*
G01Y-596600D02*
X241633Y-595933D01*
X240633Y-595600D01*
X239467Y-595434D01*
X238300Y-595767D01*
X237300Y-596433D01*
X236633Y-597433D01*
X236300Y-598767D01*
X236633Y-600100D01*
X237300Y-601100D01*
X238300Y-601767D01*
X239467Y-602100D01*
X240633Y-601933D01*
X241633Y-601433D01*
X242300Y-600767D01*
G01X247100Y-605100D02*
X248100Y-605433D01*
X249433Y-605100D01*
X250267Y-604433D01*
X250933Y-603600D01*
X251933Y-600934D01*
X254100Y-595434D01*
G01X248767D02*
X251933Y-600934D01*
G01X259400D02*
X260233Y-601600D01*
X261400Y-602100D01*
X262400D01*
X263400Y-601767D01*
X264067Y-601267D01*
X264400Y-600600D01*
X264233Y-599600D01*
X263567Y-599100D01*
X260566Y-598100D01*
X259900Y-596933D01*
X260233Y-596100D01*
X260900Y-595600D01*
X261900Y-595434D01*
X262900Y-595600D01*
X263900Y-596100D01*
G01X281667Y-602100D02*
Y-592100D01*
G01X287000Y-595434D02*
X281667Y-599267D01*
G01X283833Y-597767D02*
X287333Y-602100D01*
G01X293300Y-597600D02*
X298633D01*
X298133Y-596433D01*
X297300Y-595767D01*
X296133Y-595434D01*
X294967Y-595600D01*
X293967Y-596100D01*
X293300Y-597267D01*
X292967Y-598267D01*
Y-599267D01*
X293300Y-600267D01*
X294133Y-601267D01*
X295133Y-601933D01*
X296300Y-602100D01*
X297467Y-601767D01*
X298633Y-600767D01*
G01X304600Y-597600D02*
X309933D01*
X309433Y-596433D01*
X308600Y-595767D01*
X307433Y-595434D01*
X306267Y-595600D01*
X305267Y-596100D01*
X304600Y-597267D01*
X304267Y-598267D01*
Y-599267D01*
X304600Y-600267D01*
X305433Y-601267D01*
X306433Y-601933D01*
X307600Y-602100D01*
X308767Y-601767D01*
X309933Y-600767D01*
G01X315400Y-605433D02*
Y-595434D01*
G01Y-596933D02*
X316233Y-596100D01*
X317066Y-595600D01*
X318400Y-595434D01*
X319567Y-595600D01*
X320733Y-596433D01*
X321233Y-597600D01*
X321400Y-598767D01*
X321233Y-599933D01*
X320733Y-601100D01*
X319733Y-601767D01*
X318400Y-602100D01*
X317233Y-601933D01*
X316067Y-601433D01*
X315400Y-600767D01*
G01X337333Y-600600D02*
X338333Y-601433D01*
X339500Y-601933D01*
X341000Y-602100D01*
X342500Y-601767D01*
X343667Y-601100D01*
X344500Y-599933D01*
X344667Y-598600D01*
X344333Y-597267D01*
X343500Y-596433D01*
X342333Y-595767D01*
X341167Y-595600D01*
X340000Y-595767D01*
X338500Y-596433D01*
X339000Y-592100D01*
X343500D01*
G01X358600Y-602100D02*
Y-595434D01*
G01Y-597267D02*
X359100Y-596433D01*
X359933Y-595767D01*
X361100Y-595434D01*
X362266Y-595767D01*
X363100Y-596433D01*
X363600Y-597267D01*
Y-602100D01*
G01Y-597267D02*
X364100Y-596433D01*
X364933Y-595767D01*
X366100Y-595434D01*
X367267Y-595767D01*
X368100Y-596433D01*
X368600Y-597433D01*
Y-602100D01*
G01X374900Y-595434D02*
Y-602100D01*
G01Y-592767D02*
X374567Y-592600D01*
Y-592267D01*
X374900Y-592100D01*
X375233Y-592267D01*
Y-592600D01*
X374900Y-592767D01*
G01X386200Y-602100D02*
Y-592100D01*
G01X395000Y-600934D02*
X395833Y-601600D01*
X397000Y-602100D01*
X398000D01*
X399000Y-601767D01*
X399667Y-601267D01*
X400000Y-600600D01*
X399833Y-599600D01*
X399167Y-599100D01*
X396166Y-598100D01*
X395500Y-596933D01*
X395833Y-596100D01*
X396500Y-595600D01*
X397500Y-595434D01*
X398500Y-595600D01*
X399500Y-596100D01*
G01X409633Y-605433D02*
X411300Y-603767D01*
X412133Y-602100D01*
Y-595434D01*
X411300Y-593767D01*
X409633Y-592100D01*
G01X128467Y-529733D02*
X127467Y-529233D01*
X126300Y-528900D01*
X124967D01*
X123466Y-529400D01*
X122300Y-530233D01*
X121467Y-531233D01*
X120800Y-532900D01*
X120633Y-534400D01*
X120967Y-535900D01*
X121467Y-536900D01*
X122467Y-537900D01*
X123633Y-538567D01*
X124800Y-538900D01*
X125967D01*
X127133Y-538567D01*
X128133Y-538067D01*
X128967Y-537400D01*
G01X120333Y-341300D02*
X124500Y-331300D01*
X128667Y-341300D01*
G01X127167Y-337800D02*
X121833D01*
G01X151890Y-22420D02*
X155223D01*
Y-25420D01*
X154223Y-26420D01*
X153057Y-27087D01*
X151390Y-27420D01*
X149723Y-27087D01*
X148557Y-26420D01*
X147557Y-25420D01*
X146890Y-24253D01*
X146557Y-22920D01*
Y-21753D01*
X146890Y-20754D01*
X147557Y-19587D01*
X148557Y-18587D01*
X149556Y-17920D01*
X150890Y-17420D01*
X152057D01*
X153390Y-17753D01*
X154390Y-18420D01*
G01X165190Y-27420D02*
Y-20754D01*
G01Y-21920D02*
X164523Y-21253D01*
X163523Y-20920D01*
X162357Y-20754D01*
X161190Y-21087D01*
X160190Y-21753D01*
X159523Y-22753D01*
X159190Y-24087D01*
X159523Y-25420D01*
X160190Y-26420D01*
X161190Y-27087D01*
X162357Y-27420D01*
X163523Y-27253D01*
X164523Y-26753D01*
X165190Y-26087D01*
G01X170490Y-30753D02*
Y-20754D01*
G01Y-22253D02*
X171323Y-21420D01*
X172156Y-20920D01*
X173490Y-20754D01*
X174657Y-20920D01*
X175823Y-21753D01*
X176323Y-22920D01*
X176490Y-24087D01*
X176323Y-25253D01*
X175823Y-26420D01*
X174823Y-27087D01*
X173490Y-27420D01*
X172323Y-27253D01*
X171157Y-26753D01*
X170490Y-26087D01*
G01X191090Y-17420D02*
X193423Y-27420D01*
X196090Y-17420D01*
X198757Y-27420D01*
X201090Y-17420D01*
G01X207390Y-20754D02*
Y-27420D01*
G01Y-18087D02*
X207057Y-17920D01*
Y-17587D01*
X207390Y-17420D01*
X207723Y-17587D01*
Y-17920D01*
X207390Y-18087D01*
G01X221690Y-17420D02*
Y-27420D01*
G01Y-25920D02*
X221023Y-26753D01*
X220023Y-27253D01*
X218857Y-27420D01*
X217523Y-27087D01*
X216523Y-26254D01*
X215857Y-25253D01*
X215690Y-24087D01*
X215857Y-22920D01*
X216523Y-21920D01*
X217523Y-21087D01*
X218857Y-20754D01*
X220023Y-20920D01*
X220857Y-21253D01*
X221690Y-21920D01*
G01X229990Y-17420D02*
Y-27420D01*
G01X227657Y-20754D02*
X232323D01*
G01X238457Y-27420D02*
Y-17420D01*
G01Y-22253D02*
X239290Y-21420D01*
X240123Y-20920D01*
X241457Y-20754D01*
X242457Y-20920D01*
X243623Y-21587D01*
X244123Y-22587D01*
Y-27420D01*
G01X154330Y21180D02*
X152996Y21347D01*
X151830Y22013D01*
X150830Y23013D01*
X150163Y24180D01*
X149830Y25513D01*
Y26847D01*
X150163Y28180D01*
X150830Y29347D01*
X151830Y30347D01*
X152996Y31013D01*
X154330Y31180D01*
X155663Y31013D01*
X156830Y30347D01*
X157830Y29347D01*
X158497Y28180D01*
X158830Y26847D01*
Y25513D01*
X158497Y24180D01*
X157830Y23013D01*
X156830Y22013D01*
X155663Y21347D01*
X154330Y21180D01*
G01X162797Y27846D02*
Y23180D01*
X163463Y22013D01*
X164463Y21347D01*
X165630Y21180D01*
X166797Y21347D01*
X167797Y22013D01*
X168463Y23180D01*
G01Y21180D02*
Y27846D01*
G01X176930Y31180D02*
Y21180D01*
G01X174597Y27846D02*
X179263D01*
G01X185730Y25680D02*
X191063D01*
X190563Y26847D01*
X189730Y27513D01*
X188563Y27846D01*
X187397Y27680D01*
X186397Y27180D01*
X185730Y26013D01*
X185397Y25013D01*
Y24013D01*
X185730Y23013D01*
X186563Y22013D01*
X187563Y21347D01*
X188730Y21180D01*
X189897Y21513D01*
X191063Y22513D01*
G01X197197Y21180D02*
Y27846D01*
G01Y26513D02*
X198030Y27180D01*
X198863Y27680D01*
X200030Y27846D01*
X200863Y27680D01*
X201863Y27180D01*
G01X218463Y21180D02*
Y31180D01*
X221797D01*
X223130Y30680D01*
X224130Y30013D01*
X224963Y29013D01*
X225630Y27846D01*
X225797Y26180D01*
X225630Y24513D01*
X224963Y23347D01*
X224130Y22346D01*
X223130Y21680D01*
X221797Y21180D01*
X218463D01*
G01X233430Y27846D02*
Y21180D01*
G01Y30513D02*
X233097Y30680D01*
Y31013D01*
X233430Y31180D01*
X233763Y31013D01*
Y30680D01*
X233430Y30513D01*
G01X247730Y21180D02*
Y27846D01*
G01Y26680D02*
X247063Y27347D01*
X246063Y27680D01*
X244897Y27846D01*
X243730Y27513D01*
X242730Y26847D01*
X242063Y25847D01*
X241730Y24513D01*
X242063Y23180D01*
X242730Y22180D01*
X243730Y21513D01*
X244897Y21180D01*
X246063Y21347D01*
X247063Y21847D01*
X247730Y22513D01*
G01X251030Y21180D02*
Y27846D01*
G01Y26013D02*
X251530Y26847D01*
X252363Y27513D01*
X253530Y27846D01*
X254696Y27513D01*
X255530Y26847D01*
X256030Y26013D01*
Y21180D01*
G01Y26013D02*
X256530Y26847D01*
X257363Y27513D01*
X258530Y27846D01*
X259697Y27513D01*
X260530Y26847D01*
X261030Y25847D01*
Y21180D01*
G01X264830Y25680D02*
X270163D01*
X269663Y26847D01*
X268830Y27513D01*
X267663Y27846D01*
X266497Y27680D01*
X265497Y27180D01*
X264830Y26013D01*
X264497Y25013D01*
Y24013D01*
X264830Y23013D01*
X265663Y22013D01*
X266663Y21347D01*
X267830Y21180D01*
X268997Y21513D01*
X270163Y22513D01*
G01X278630Y31180D02*
Y21180D01*
G01X276297Y27846D02*
X280963D01*
G01X287430Y25680D02*
X292763D01*
X292263Y26847D01*
X291430Y27513D01*
X290263Y27846D01*
X289097Y27680D01*
X288097Y27180D01*
X287430Y26013D01*
X287097Y25013D01*
Y24013D01*
X287430Y23013D01*
X288263Y22013D01*
X289263Y21347D01*
X290430Y21180D01*
X291597Y21513D01*
X292763Y22513D01*
G01X298897Y21180D02*
Y27846D01*
G01Y26513D02*
X299730Y27180D01*
X300563Y27680D01*
X301730Y27846D01*
X302563Y27680D01*
X303563Y27180D01*
G01X193433Y-427567D02*
X194100Y-427067D01*
X194600Y-426234D01*
X194933Y-425067D01*
X194600Y-424067D01*
X193933Y-423400D01*
X192767Y-422900D01*
X188267D01*
Y-432900D01*
X193767D01*
X194933Y-432233D01*
X195600Y-431233D01*
X195933Y-430067D01*
X195600Y-428900D01*
X194600Y-427900D01*
X193433Y-427567D01*
X188267D01*
G01X221400Y-131100D02*
X220066Y-130933D01*
X218900Y-130267D01*
X217900Y-129267D01*
X217233Y-128100D01*
X216900Y-126767D01*
Y-125433D01*
X217233Y-124100D01*
X217900Y-122933D01*
X218900Y-121933D01*
X220066Y-121267D01*
X221400Y-121100D01*
X222733Y-121267D01*
X223900Y-121933D01*
X224900Y-122933D01*
X225567Y-124100D01*
X225900Y-125433D01*
Y-126767D01*
X225567Y-128100D01*
X224900Y-129267D01*
X223900Y-130267D01*
X222733Y-130933D01*
X221400Y-131100D01*
G01X229867Y-124434D02*
Y-129100D01*
X230533Y-130267D01*
X231533Y-130933D01*
X232700Y-131100D01*
X233867Y-130933D01*
X234867Y-130267D01*
X235533Y-129100D01*
G01Y-131100D02*
Y-124434D01*
G01X244000Y-121100D02*
Y-131100D01*
G01X241667Y-124434D02*
X246333D01*
G01X252800Y-126600D02*
X258133D01*
X257633Y-125433D01*
X256800Y-124767D01*
X255633Y-124434D01*
X254467Y-124600D01*
X253467Y-125100D01*
X252800Y-126267D01*
X252467Y-127267D01*
Y-128267D01*
X252800Y-129267D01*
X253633Y-130267D01*
X254633Y-130933D01*
X255800Y-131100D01*
X256967Y-130767D01*
X258133Y-129767D01*
G01X264267Y-131100D02*
Y-124434D01*
G01Y-125767D02*
X265100Y-125100D01*
X265933Y-124600D01*
X267100Y-124434D01*
X267933Y-124600D01*
X268933Y-125100D01*
G01X285533Y-131100D02*
Y-121100D01*
X288867D01*
X290200Y-121600D01*
X291200Y-122267D01*
X292033Y-123267D01*
X292700Y-124434D01*
X292867Y-126100D01*
X292700Y-127767D01*
X292033Y-128933D01*
X291200Y-129934D01*
X290200Y-130600D01*
X288867Y-131100D01*
X285533D01*
G01X300500Y-124434D02*
Y-131100D01*
G01Y-121767D02*
X300167Y-121600D01*
Y-121267D01*
X300500Y-121100D01*
X300833Y-121267D01*
Y-121600D01*
X300500Y-121767D01*
G01X314800Y-131100D02*
Y-124434D01*
G01Y-125600D02*
X314133Y-124933D01*
X313133Y-124600D01*
X311967Y-124434D01*
X310800Y-124767D01*
X309800Y-125433D01*
X309133Y-126433D01*
X308800Y-127767D01*
X309133Y-129100D01*
X309800Y-130100D01*
X310800Y-130767D01*
X311967Y-131100D01*
X313133Y-130933D01*
X314133Y-130433D01*
X314800Y-129767D01*
G01X318100Y-131100D02*
Y-124434D01*
G01Y-126267D02*
X318600Y-125433D01*
X319433Y-124767D01*
X320600Y-124434D01*
X321766Y-124767D01*
X322600Y-125433D01*
X323100Y-126267D01*
Y-131100D01*
G01Y-126267D02*
X323600Y-125433D01*
X324433Y-124767D01*
X325600Y-124434D01*
X326767Y-124767D01*
X327600Y-125433D01*
X328100Y-126433D01*
Y-131100D01*
G01X331900Y-126600D02*
X337233D01*
X336733Y-125433D01*
X335900Y-124767D01*
X334733Y-124434D01*
X333567Y-124600D01*
X332567Y-125100D01*
X331900Y-126267D01*
X331567Y-127267D01*
Y-128267D01*
X331900Y-129267D01*
X332733Y-130267D01*
X333733Y-130933D01*
X334900Y-131100D01*
X336067Y-130767D01*
X337233Y-129767D01*
G01X345700Y-121100D02*
Y-131100D01*
G01X343367Y-124434D02*
X348033D01*
G01X354500Y-126600D02*
X359833D01*
X359333Y-125433D01*
X358500Y-124767D01*
X357333Y-124434D01*
X356167Y-124600D01*
X355167Y-125100D01*
X354500Y-126267D01*
X354167Y-127267D01*
Y-128267D01*
X354500Y-129267D01*
X355333Y-130267D01*
X356333Y-130933D01*
X357500Y-131100D01*
X358667Y-130767D01*
X359833Y-129767D01*
G01X365967Y-131100D02*
Y-124434D01*
G01Y-125767D02*
X366800Y-125100D01*
X367633Y-124600D01*
X368800Y-124434D01*
X369633Y-124600D01*
X370633Y-125100D01*
G01X377433Y-129267D02*
X381767D01*
G01Y-126267D02*
X377433D01*
G01X390900Y-131100D02*
Y-121100D01*
X388900Y-123100D01*
G01Y-131100D02*
X392900D01*
G01X402200Y-121100D02*
X400866Y-121433D01*
X399867Y-122267D01*
X399200Y-123267D01*
X398700Y-124600D01*
X398533Y-126100D01*
X398700Y-127600D01*
X399200Y-128933D01*
X399867Y-129934D01*
X400866Y-130767D01*
X402200Y-131100D01*
X403533Y-130767D01*
X404533Y-129934D01*
X405200Y-128933D01*
X405700Y-127600D01*
X405867Y-126100D01*
X405700Y-124600D01*
X405200Y-123267D01*
X404533Y-122267D01*
X403533Y-121433D01*
X402200Y-121100D01*
G01X409833Y-129100D02*
X410833Y-130267D01*
X412166Y-130933D01*
X413667Y-131100D01*
X415000Y-130933D01*
X416333Y-130100D01*
X417167Y-129100D01*
X417333Y-128100D01*
X417000Y-126934D01*
X415833Y-126100D01*
X414667Y-125767D01*
X413167D01*
G01X414667D02*
X415667Y-125267D01*
X416500Y-124434D01*
X416833Y-123433D01*
X416500Y-122433D01*
X415667Y-121600D01*
X414167Y-121100D01*
X412667Y-121267D01*
X411167Y-121933D01*
G01X222400Y-162100D02*
X225733D01*
Y-165100D01*
X224733Y-166100D01*
X223567Y-166767D01*
X221900Y-167100D01*
X220233Y-166767D01*
X219067Y-166100D01*
X218067Y-165100D01*
X217400Y-163933D01*
X217067Y-162600D01*
Y-161433D01*
X217400Y-160434D01*
X218067Y-159267D01*
X219067Y-158267D01*
X220066Y-157600D01*
X221400Y-157100D01*
X222567D01*
X223900Y-157433D01*
X224900Y-158100D01*
G01X235700Y-167100D02*
Y-160434D01*
G01Y-161600D02*
X235033Y-160933D01*
X234033Y-160600D01*
X232867Y-160434D01*
X231700Y-160767D01*
X230700Y-161433D01*
X230033Y-162433D01*
X229700Y-163767D01*
X230033Y-165100D01*
X230700Y-166100D01*
X231700Y-166767D01*
X232867Y-167100D01*
X234033Y-166933D01*
X235033Y-166433D01*
X235700Y-165767D01*
G01X241000Y-170433D02*
Y-160434D01*
G01Y-161933D02*
X241833Y-161100D01*
X242666Y-160600D01*
X244000Y-160434D01*
X245167Y-160600D01*
X246333Y-161433D01*
X246833Y-162600D01*
X247000Y-163767D01*
X246833Y-164933D01*
X246333Y-166100D01*
X245333Y-166767D01*
X244000Y-167100D01*
X242833Y-166933D01*
X241667Y-166433D01*
X241000Y-165767D01*
G01X261600Y-157100D02*
X263933Y-167100D01*
X266600Y-157100D01*
X269267Y-167100D01*
X271600Y-157100D01*
G01X277900Y-160434D02*
Y-167100D01*
G01Y-157767D02*
X277567Y-157600D01*
Y-157267D01*
X277900Y-157100D01*
X278233Y-157267D01*
Y-157600D01*
X277900Y-157767D01*
G01X292200Y-157100D02*
Y-167100D01*
G01Y-165600D02*
X291533Y-166433D01*
X290533Y-166933D01*
X289367Y-167100D01*
X288033Y-166767D01*
X287033Y-165934D01*
X286367Y-164933D01*
X286200Y-163767D01*
X286367Y-162600D01*
X287033Y-161600D01*
X288033Y-160767D01*
X289367Y-160434D01*
X290533Y-160600D01*
X291367Y-160933D01*
X292200Y-161600D01*
G01X300500Y-157100D02*
Y-167100D01*
G01X298167Y-160434D02*
X302833D01*
G01X308967Y-167100D02*
Y-157100D01*
G01Y-161933D02*
X309800Y-161100D01*
X310633Y-160600D01*
X311967Y-160434D01*
X312967Y-160600D01*
X314133Y-161267D01*
X314633Y-162267D01*
Y-167100D01*
G01X320933Y-165267D02*
X325267D01*
G01Y-162267D02*
X320933D01*
G01X330733Y-165100D02*
X331733Y-166267D01*
X333066Y-166933D01*
X334567Y-167100D01*
X335900Y-166933D01*
X337233Y-166100D01*
X338067Y-165100D01*
X338233Y-164100D01*
X337900Y-162934D01*
X336733Y-162100D01*
X335567Y-161767D01*
X334067D01*
G01X335567D02*
X336567Y-161267D01*
X337400Y-160434D01*
X337733Y-159433D01*
X337400Y-158433D01*
X336567Y-157600D01*
X335067Y-157100D01*
X333567Y-157267D01*
X332067Y-157933D01*
G01X345700Y-157100D02*
X344366Y-157433D01*
X343367Y-158267D01*
X342700Y-159267D01*
X342200Y-160600D01*
X342033Y-162100D01*
X342200Y-163600D01*
X342700Y-164933D01*
X343367Y-165934D01*
X344366Y-166767D01*
X345700Y-167100D01*
X347033Y-166767D01*
X348033Y-165934D01*
X348700Y-164933D01*
X349200Y-163600D01*
X349367Y-162100D01*
X349200Y-160600D01*
X348700Y-159267D01*
X348033Y-158267D01*
X347033Y-157433D01*
X345700Y-157100D01*
G01X219567Y-151100D02*
Y-141100D01*
X227233Y-151100D01*
Y-141100D01*
G01X231867Y-144434D02*
Y-149100D01*
X232533Y-150267D01*
X233533Y-150933D01*
X234700Y-151100D01*
X235867Y-150933D01*
X236867Y-150267D01*
X237533Y-149100D01*
G01Y-151100D02*
Y-144434D01*
G01X241000Y-151100D02*
Y-144434D01*
G01Y-146267D02*
X241500Y-145433D01*
X242333Y-144767D01*
X243500Y-144434D01*
X244666Y-144767D01*
X245500Y-145433D01*
X246000Y-146267D01*
Y-151100D01*
G01Y-146267D02*
X246500Y-145433D01*
X247333Y-144767D01*
X248500Y-144434D01*
X249667Y-144767D01*
X250500Y-145433D01*
X251000Y-146433D01*
Y-151100D01*
G01X265100Y-149767D02*
X266433Y-150600D01*
X267933Y-151100D01*
X269267D01*
X270600Y-150600D01*
X271600Y-149767D01*
X272100Y-148600D01*
X271767Y-147434D01*
X270933Y-146433D01*
X269433Y-145767D01*
X267433Y-145433D01*
X266267Y-144767D01*
X265767Y-143600D01*
X266100Y-142433D01*
X266933Y-141600D01*
X268100Y-141100D01*
X269267D01*
X270433Y-141433D01*
X271433Y-142267D01*
G01X276900Y-154433D02*
Y-144434D01*
G01Y-145933D02*
X277733Y-145100D01*
X278566Y-144600D01*
X279900Y-144434D01*
X281067Y-144600D01*
X282233Y-145433D01*
X282733Y-146600D01*
X282900Y-147767D01*
X282733Y-148933D01*
X282233Y-150100D01*
X281233Y-150767D01*
X279900Y-151100D01*
X278733Y-150933D01*
X277567Y-150433D01*
X276900Y-149767D01*
G01X291200Y-151100D02*
X290200Y-150933D01*
X289200Y-150267D01*
X288533Y-149100D01*
X288200Y-147767D01*
X288533Y-146433D01*
X289200Y-145267D01*
X290200Y-144600D01*
X291200Y-144434D01*
X292200Y-144600D01*
X293200Y-145267D01*
X293867Y-146433D01*
X294033Y-147767D01*
X293867Y-149100D01*
X293200Y-150267D01*
X292200Y-150933D01*
X291200Y-151100D01*
G01X299667D02*
Y-141100D01*
G01X305000Y-144434D02*
X299667Y-148267D01*
G01X301833Y-146767D02*
X305333Y-151100D01*
G01X311300Y-146600D02*
X316633D01*
X316133Y-145433D01*
X315300Y-144767D01*
X314133Y-144434D01*
X312967Y-144600D01*
X311967Y-145100D01*
X311300Y-146267D01*
X310967Y-147267D01*
Y-148267D01*
X311300Y-149267D01*
X312133Y-150267D01*
X313133Y-150933D01*
X314300Y-151100D01*
X315467Y-150767D01*
X316633Y-149767D01*
G01X322600Y-149934D02*
X323433Y-150600D01*
X324600Y-151100D01*
X325600D01*
X326600Y-150767D01*
X327267Y-150267D01*
X327600Y-149600D01*
X327433Y-148600D01*
X326767Y-148100D01*
X323766Y-147100D01*
X323100Y-145933D01*
X323433Y-145100D01*
X324100Y-144600D01*
X325100Y-144434D01*
X326100Y-144600D01*
X327100Y-145100D01*
G01X334233Y-149267D02*
X338567D01*
G01Y-146267D02*
X334233D01*
G01X349700Y-151100D02*
Y-141100D01*
X343533Y-148267D01*
X351867D01*
G01X217400Y-99100D02*
X221400D01*
G01X219400D02*
Y-109100D01*
G01X217400D02*
X221400D01*
G01X227867D02*
Y-102434D01*
G01Y-104100D02*
X228533Y-103267D01*
X229533Y-102600D01*
X230867Y-102434D01*
X232033Y-102600D01*
X233033Y-103267D01*
X233533Y-104433D01*
Y-109100D01*
G01X239167D02*
Y-102434D01*
G01Y-104100D02*
X239833Y-103267D01*
X240833Y-102600D01*
X242167Y-102434D01*
X243333Y-102600D01*
X244333Y-103267D01*
X244833Y-104433D01*
Y-109100D01*
G01X250800Y-104600D02*
X256133D01*
X255633Y-103433D01*
X254800Y-102767D01*
X253633Y-102434D01*
X252467Y-102600D01*
X251467Y-103100D01*
X250800Y-104267D01*
X250467Y-105267D01*
Y-106267D01*
X250800Y-107267D01*
X251633Y-108267D01*
X252633Y-108933D01*
X253800Y-109100D01*
X254967Y-108767D01*
X256133Y-107767D01*
G01X262267Y-109100D02*
Y-102434D01*
G01Y-103767D02*
X263100Y-103100D01*
X263933Y-102600D01*
X265100Y-102434D01*
X265933Y-102600D01*
X266933Y-103100D01*
G01X283533Y-109100D02*
Y-99100D01*
X286867D01*
X288200Y-99600D01*
X289200Y-100267D01*
X290033Y-101267D01*
X290700Y-102434D01*
X290867Y-104100D01*
X290700Y-105767D01*
X290033Y-106933D01*
X289200Y-107934D01*
X288200Y-108600D01*
X286867Y-109100D01*
X283533D01*
G01X298500Y-102434D02*
Y-109100D01*
G01Y-99767D02*
X298167Y-99600D01*
Y-99267D01*
X298500Y-99100D01*
X298833Y-99267D01*
Y-99600D01*
X298500Y-99767D01*
G01X312800Y-109100D02*
Y-102434D01*
G01Y-103600D02*
X312133Y-102933D01*
X311133Y-102600D01*
X309967Y-102434D01*
X308800Y-102767D01*
X307800Y-103433D01*
X307133Y-104433D01*
X306800Y-105767D01*
X307133Y-107100D01*
X307800Y-108100D01*
X308800Y-108767D01*
X309967Y-109100D01*
X311133Y-108933D01*
X312133Y-108433D01*
X312800Y-107767D01*
G01X316100Y-109100D02*
Y-102434D01*
G01Y-104267D02*
X316600Y-103433D01*
X317433Y-102767D01*
X318600Y-102434D01*
X319766Y-102767D01*
X320600Y-103433D01*
X321100Y-104267D01*
Y-109100D01*
G01Y-104267D02*
X321600Y-103433D01*
X322433Y-102767D01*
X323600Y-102434D01*
X324767Y-102767D01*
X325600Y-103433D01*
X326100Y-104433D01*
Y-109100D01*
G01X329900Y-104600D02*
X335233D01*
X334733Y-103433D01*
X333900Y-102767D01*
X332733Y-102434D01*
X331567Y-102600D01*
X330567Y-103100D01*
X329900Y-104267D01*
X329567Y-105267D01*
Y-106267D01*
X329900Y-107267D01*
X330733Y-108267D01*
X331733Y-108933D01*
X332900Y-109100D01*
X334067Y-108767D01*
X335233Y-107767D01*
G01X343700Y-99100D02*
Y-109100D01*
G01X341367Y-102434D02*
X346033D01*
G01X352500Y-104600D02*
X357833D01*
X357333Y-103433D01*
X356500Y-102767D01*
X355333Y-102434D01*
X354167Y-102600D01*
X353167Y-103100D01*
X352500Y-104267D01*
X352167Y-105267D01*
Y-106267D01*
X352500Y-107267D01*
X353333Y-108267D01*
X354333Y-108933D01*
X355500Y-109100D01*
X356667Y-108767D01*
X357833Y-107767D01*
G01X363967Y-109100D02*
Y-102434D01*
G01Y-103767D02*
X364800Y-103100D01*
X365633Y-102600D01*
X366800Y-102434D01*
X367633Y-102600D01*
X368633Y-103100D01*
G01X375433Y-107267D02*
X379767D01*
G01Y-104267D02*
X375433D01*
G01X386067Y-107934D02*
X387233Y-108767D01*
X388567Y-109100D01*
X389900Y-108767D01*
X391067Y-107767D01*
X391900Y-106267D01*
X392233Y-104767D01*
Y-102933D01*
X391900Y-101433D01*
X391067Y-100100D01*
X390067Y-99433D01*
X388900Y-99100D01*
X387566Y-99433D01*
X386567Y-100100D01*
X385900Y-101100D01*
X385567Y-102434D01*
X385900Y-103600D01*
X386733Y-104767D01*
X387733Y-105434D01*
X388900Y-105600D01*
X390233Y-105267D01*
X391233Y-104433D01*
X392233Y-102933D01*
G01X396533Y-107100D02*
X397533Y-108267D01*
X398866Y-108933D01*
X400367Y-109100D01*
X401700Y-108933D01*
X403033Y-108100D01*
X403867Y-107100D01*
X404033Y-106100D01*
X403700Y-104934D01*
X402533Y-104100D01*
X401367Y-103767D01*
X399867D01*
G01X401367D02*
X402367Y-103267D01*
X403200Y-102434D01*
X403533Y-101433D01*
X403200Y-100433D01*
X402367Y-99600D01*
X400867Y-99100D01*
X399367Y-99267D01*
X397867Y-99933D01*
G54D12*
G01X530200Y-653000D02*
Y-645000D01*
X534000D01*
G01X532600Y-648867D02*
X530200D01*
G01X540100Y-653000D02*
X539500Y-652867D01*
X538900Y-652333D01*
X538500Y-651400D01*
X538300Y-650333D01*
X538500Y-649267D01*
X538900Y-648333D01*
X539500Y-647800D01*
X540100Y-647667D01*
X540700Y-647800D01*
X541300Y-648333D01*
X541700Y-649267D01*
X541800Y-650333D01*
X541700Y-651400D01*
X541300Y-652333D01*
X540700Y-652867D01*
X540100Y-653000D01*
G01X546700D02*
Y-647667D01*
G01Y-648733D02*
X547200Y-648200D01*
X547700Y-647800D01*
X548400Y-647667D01*
X548900Y-647800D01*
X549500Y-648200D01*
G01X562600Y-649400D02*
X565800D01*
X565500Y-648467D01*
X565000Y-647933D01*
X564300Y-647667D01*
X563600Y-647800D01*
X563000Y-648200D01*
X562600Y-649133D01*
X562400Y-649934D01*
Y-650733D01*
X562600Y-651533D01*
X563100Y-652333D01*
X563700Y-652867D01*
X564400Y-653000D01*
X565100Y-652733D01*
X565800Y-651934D01*
G01X570600Y-647667D02*
X573600Y-653000D01*
G01Y-647667D02*
X570600Y-653000D01*
G01X581900D02*
Y-647667D01*
G01Y-648600D02*
X581500Y-648067D01*
X580900Y-647800D01*
X580200Y-647667D01*
X579500Y-647933D01*
X578900Y-648467D01*
X578500Y-649267D01*
X578300Y-650333D01*
X578500Y-651400D01*
X578900Y-652200D01*
X579500Y-652733D01*
X580200Y-653000D01*
X580900Y-652867D01*
X581500Y-652467D01*
X581900Y-651934D01*
G01X585100Y-653000D02*
Y-647667D01*
G01Y-649133D02*
X585400Y-648467D01*
X585900Y-647933D01*
X586600Y-647667D01*
X587300Y-647933D01*
X587800Y-648467D01*
X588100Y-649133D01*
Y-653000D01*
G01Y-649133D02*
X588400Y-648467D01*
X588900Y-647933D01*
X589600Y-647667D01*
X590300Y-647933D01*
X590800Y-648467D01*
X591100Y-649267D01*
Y-653000D01*
G01X594300Y-655667D02*
Y-647667D01*
G01Y-648867D02*
X594800Y-648200D01*
X595300Y-647800D01*
X596100Y-647667D01*
X596800Y-647800D01*
X597500Y-648467D01*
X597800Y-649400D01*
X597900Y-650333D01*
X597800Y-651267D01*
X597500Y-652200D01*
X596900Y-652733D01*
X596100Y-653000D01*
X595400Y-652867D01*
X594700Y-652467D01*
X594300Y-651934D01*
G01X604100Y-653000D02*
Y-645000D01*
G01X610600Y-649400D02*
X613800D01*
X613500Y-648467D01*
X613000Y-647933D01*
X612300Y-647667D01*
X611600Y-647800D01*
X611000Y-648200D01*
X610600Y-649133D01*
X610400Y-649934D01*
Y-650733D01*
X610600Y-651533D01*
X611100Y-652333D01*
X611700Y-652867D01*
X612400Y-653000D01*
X613100Y-652733D01*
X613800Y-651934D01*
G01X620100Y-653267D02*
X619900Y-653133D01*
Y-652867D01*
X620100Y-652733D01*
X620300Y-652867D01*
Y-653133D01*
X620100Y-653267D01*
G01Y-649667D02*
X619900Y-649533D01*
Y-649267D01*
X620100Y-649133D01*
X620300Y-649267D01*
Y-649533D01*
X620100Y-649667D01*
G01X634000Y-653000D02*
Y-645000D01*
G01X638200D02*
Y-653000D01*
G01Y-649000D02*
X634000D01*
G01X644100Y-653000D02*
X643500Y-652867D01*
X642900Y-652333D01*
X642500Y-651400D01*
X642300Y-650333D01*
X642500Y-649267D01*
X642900Y-648333D01*
X643500Y-647800D01*
X644100Y-647667D01*
X644700Y-647800D01*
X645300Y-648333D01*
X645700Y-649267D01*
X645800Y-650333D01*
X645700Y-651400D01*
X645300Y-652333D01*
X644700Y-652867D01*
X644100Y-653000D01*
G01X652100D02*
Y-645000D01*
G01X658600Y-649400D02*
X661800D01*
X661500Y-648467D01*
X661000Y-647933D01*
X660300Y-647667D01*
X659600Y-647800D01*
X659000Y-648200D01*
X658600Y-649133D01*
X658400Y-649934D01*
Y-650733D01*
X658600Y-651533D01*
X659100Y-652333D01*
X659700Y-652867D01*
X660400Y-653000D01*
X661100Y-652733D01*
X661800Y-651934D01*
G01X673900Y-653000D02*
Y-645000D01*
X675900D01*
X676700Y-645400D01*
X677300Y-645933D01*
X677800Y-646733D01*
X678200Y-647667D01*
X678300Y-649000D01*
X678200Y-650333D01*
X677800Y-651267D01*
X677300Y-652067D01*
X676700Y-652600D01*
X675900Y-653000D01*
X673900D01*
G01X684100Y-647667D02*
Y-653000D01*
G01Y-645533D02*
X683900Y-645400D01*
Y-645133D01*
X684100Y-645000D01*
X684300Y-645133D01*
Y-645400D01*
X684100Y-645533D01*
G01X693900Y-653000D02*
Y-647667D01*
G01Y-648600D02*
X693500Y-648067D01*
X692900Y-647800D01*
X692200Y-647667D01*
X691500Y-647933D01*
X690900Y-648467D01*
X690500Y-649267D01*
X690300Y-650333D01*
X690500Y-651400D01*
X690900Y-652200D01*
X691500Y-652733D01*
X692200Y-653000D01*
X692900Y-652867D01*
X693500Y-652467D01*
X693900Y-651934D01*
G01X700100Y-653267D02*
X699900Y-653133D01*
Y-652867D01*
X700100Y-652733D01*
X700300Y-652867D01*
Y-653133D01*
X700100Y-653267D01*
G01X705900Y-651400D02*
X706500Y-652333D01*
X707300Y-652867D01*
X708200Y-653000D01*
X709000Y-652867D01*
X709800Y-652200D01*
X710300Y-651400D01*
X710400Y-650600D01*
X710200Y-649667D01*
X709500Y-649000D01*
X708800Y-648733D01*
X707900D01*
G01X708800D02*
X709400Y-648333D01*
X709900Y-647667D01*
X710100Y-646867D01*
X709900Y-646067D01*
X709400Y-645400D01*
X708500Y-645000D01*
X707600Y-645133D01*
X706700Y-645667D01*
G01X716100Y-653267D02*
X715900Y-653133D01*
Y-652867D01*
X716100Y-652733D01*
X716300Y-652867D01*
Y-653133D01*
X716100Y-653267D01*
G01X724100Y-653000D02*
Y-645000D01*
X722900Y-646600D01*
G01Y-653000D02*
X725300D01*
G01X732100D02*
X732800Y-652867D01*
X733600Y-652467D01*
X734100Y-651800D01*
X734300Y-650867D01*
X734100Y-649934D01*
X733500Y-649133D01*
X732600Y-648733D01*
X731600D01*
X731000Y-648467D01*
X730500Y-647800D01*
X730300Y-646867D01*
X730600Y-645933D01*
X731300Y-645267D01*
X732100Y-645000D01*
X732900Y-645267D01*
X733600Y-645933D01*
X733900Y-646867D01*
X733700Y-647800D01*
X733200Y-648467D01*
X732600Y-648733D01*
X731600D01*
X730700Y-649133D01*
X730100Y-649934D01*
X729900Y-650867D01*
X730100Y-651800D01*
X730600Y-652467D01*
X731400Y-652867D01*
X732100Y-653000D01*
G01X737100D02*
Y-647667D01*
G01Y-649133D02*
X737400Y-648467D01*
X737900Y-647933D01*
X738600Y-647667D01*
X739300Y-647933D01*
X739800Y-648467D01*
X740100Y-649133D01*
Y-653000D01*
G01Y-649133D02*
X740400Y-648467D01*
X740900Y-647933D01*
X741600Y-647667D01*
X742300Y-647933D01*
X742800Y-648467D01*
X743100Y-649267D01*
Y-653000D01*
G01X745100D02*
Y-647667D01*
G01Y-649133D02*
X745400Y-648467D01*
X745900Y-647933D01*
X746600Y-647667D01*
X747300Y-647933D01*
X747800Y-648467D01*
X748100Y-649133D01*
Y-653000D01*
G01Y-649133D02*
X748400Y-648467D01*
X748900Y-647933D01*
X749600Y-647667D01*
X750300Y-647933D01*
X750800Y-648467D01*
X751100Y-649267D01*
Y-653000D01*
G01X764100Y-647667D02*
Y-653000D01*
G01Y-645533D02*
X763900Y-645400D01*
Y-645133D01*
X764100Y-645000D01*
X764300Y-645133D01*
Y-645400D01*
X764100Y-645533D01*
G01X770600Y-652067D02*
X771100Y-652600D01*
X771800Y-653000D01*
X772400D01*
X773000Y-652733D01*
X773400Y-652333D01*
X773600Y-651800D01*
X773500Y-651000D01*
X773100Y-650600D01*
X771300Y-649800D01*
X770900Y-648867D01*
X771100Y-648200D01*
X771500Y-647800D01*
X772100Y-647667D01*
X772700Y-647800D01*
X773300Y-648200D01*
G01X785100Y-653000D02*
Y-647667D01*
G01Y-649133D02*
X785400Y-648467D01*
X785900Y-647933D01*
X786600Y-647667D01*
X787300Y-647933D01*
X787800Y-648467D01*
X788100Y-649133D01*
Y-653000D01*
G01Y-649133D02*
X788400Y-648467D01*
X788900Y-647933D01*
X789600Y-647667D01*
X790300Y-647933D01*
X790800Y-648467D01*
X791100Y-649267D01*
Y-653000D01*
G01X797900D02*
Y-647667D01*
G01Y-648600D02*
X797500Y-648067D01*
X796900Y-647800D01*
X796200Y-647667D01*
X795500Y-647933D01*
X794900Y-648467D01*
X794500Y-649267D01*
X794300Y-650333D01*
X794500Y-651400D01*
X794900Y-652200D01*
X795500Y-652733D01*
X796200Y-653000D01*
X796900Y-652867D01*
X797500Y-652467D01*
X797900Y-651934D01*
G01X802700Y-653000D02*
Y-647667D01*
G01Y-648733D02*
X803200Y-648200D01*
X803700Y-647800D01*
X804400Y-647667D01*
X804900Y-647800D01*
X805500Y-648200D01*
G01X810400Y-653000D02*
Y-645000D01*
G01X813600Y-647667D02*
X810400Y-650733D01*
G01X811700Y-649533D02*
X813800Y-653000D01*
G01X818600Y-649400D02*
X821800D01*
X821500Y-648467D01*
X821000Y-647933D01*
X820300Y-647667D01*
X819600Y-647800D01*
X819000Y-648200D01*
X818600Y-649133D01*
X818400Y-649934D01*
Y-650733D01*
X818600Y-651533D01*
X819100Y-652333D01*
X819700Y-652867D01*
X820400Y-653000D01*
X821100Y-652733D01*
X821800Y-651934D01*
G01X829900Y-645000D02*
Y-653000D01*
G01Y-651800D02*
X829500Y-652467D01*
X828900Y-652867D01*
X828200Y-653000D01*
X827400Y-652733D01*
X826800Y-652067D01*
X826400Y-651267D01*
X826300Y-650333D01*
X826400Y-649400D01*
X826800Y-648600D01*
X827400Y-647933D01*
X828200Y-647667D01*
X828900Y-647800D01*
X829400Y-648067D01*
X829900Y-648600D01*
G01X844100Y-647667D02*
Y-653000D01*
G01Y-645533D02*
X843900Y-645400D01*
Y-645133D01*
X844100Y-645000D01*
X844300Y-645133D01*
Y-645400D01*
X844100Y-645533D01*
G01X850400Y-653000D02*
Y-647667D01*
G01Y-649000D02*
X850800Y-648333D01*
X851400Y-647800D01*
X852200Y-647667D01*
X852900Y-647800D01*
X853500Y-648333D01*
X853800Y-649267D01*
Y-653000D01*
G01X865100D02*
Y-647667D01*
G01Y-649133D02*
X865400Y-648467D01*
X865900Y-647933D01*
X866600Y-647667D01*
X867300Y-647933D01*
X867800Y-648467D01*
X868100Y-649133D01*
Y-653000D01*
G01Y-649133D02*
X868400Y-648467D01*
X868900Y-647933D01*
X869600Y-647667D01*
X870300Y-647933D01*
X870800Y-648467D01*
X871100Y-649267D01*
Y-653000D01*
G01X874600Y-649400D02*
X877800D01*
X877500Y-648467D01*
X877000Y-647933D01*
X876300Y-647667D01*
X875600Y-647800D01*
X875000Y-648200D01*
X874600Y-649133D01*
X874400Y-649934D01*
Y-650733D01*
X874600Y-651533D01*
X875100Y-652333D01*
X875700Y-652867D01*
X876400Y-653000D01*
X877100Y-652733D01*
X877800Y-651934D01*
G01X885700Y-648333D02*
X885000Y-647800D01*
X884400Y-647667D01*
X883600Y-647933D01*
X883000Y-648467D01*
X882600Y-649400D01*
X882500Y-650333D01*
X882600Y-651267D01*
X883000Y-652067D01*
X883600Y-652733D01*
X884400Y-653000D01*
X885100Y-652733D01*
X885700Y-652200D01*
G01X890400Y-653000D02*
Y-645000D01*
G01Y-648867D02*
X890900Y-648200D01*
X891400Y-647800D01*
X892200Y-647667D01*
X892800Y-647800D01*
X893500Y-648333D01*
X893800Y-649133D01*
Y-653000D01*
G01X901900D02*
Y-647667D01*
G01Y-648600D02*
X901500Y-648067D01*
X900900Y-647800D01*
X900200Y-647667D01*
X899500Y-647933D01*
X898900Y-648467D01*
X898500Y-649267D01*
X898300Y-650333D01*
X898500Y-651400D01*
X898900Y-652200D01*
X899500Y-652733D01*
X900200Y-653000D01*
X900900Y-652867D01*
X901500Y-652467D01*
X901900Y-651934D01*
G01X906400Y-653000D02*
Y-647667D01*
G01Y-649000D02*
X906800Y-648333D01*
X907400Y-647800D01*
X908200Y-647667D01*
X908900Y-647800D01*
X909500Y-648333D01*
X909800Y-649267D01*
Y-653000D01*
G01X916100Y-647667D02*
Y-653000D01*
G01Y-645533D02*
X915900Y-645400D01*
Y-645133D01*
X916100Y-645000D01*
X916300Y-645133D01*
Y-645400D01*
X916100Y-645533D01*
G01X925700Y-648333D02*
X925000Y-647800D01*
X924400Y-647667D01*
X923600Y-647933D01*
X923000Y-648467D01*
X922600Y-649400D01*
X922500Y-650333D01*
X922600Y-651267D01*
X923000Y-652067D01*
X923600Y-652733D01*
X924400Y-653000D01*
X925100Y-652733D01*
X925700Y-652200D01*
G01X933900Y-653000D02*
Y-647667D01*
G01Y-648600D02*
X933500Y-648067D01*
X932900Y-647800D01*
X932200Y-647667D01*
X931500Y-647933D01*
X930900Y-648467D01*
X930500Y-649267D01*
X930300Y-650333D01*
X930500Y-651400D01*
X930900Y-652200D01*
X931500Y-652733D01*
X932200Y-653000D01*
X932900Y-652867D01*
X933500Y-652467D01*
X933900Y-651934D01*
G01X940100Y-653000D02*
Y-645000D01*
G01X957900D02*
Y-653000D01*
G01Y-651800D02*
X957500Y-652467D01*
X956900Y-652867D01*
X956200Y-653000D01*
X955400Y-652733D01*
X954800Y-652067D01*
X954400Y-651267D01*
X954300Y-650333D01*
X954400Y-649400D01*
X954800Y-648600D01*
X955400Y-647933D01*
X956200Y-647667D01*
X956900Y-647800D01*
X957400Y-648067D01*
X957900Y-648600D01*
G01X962700Y-653000D02*
Y-647667D01*
G01Y-648733D02*
X963200Y-648200D01*
X963700Y-647800D01*
X964400Y-647667D01*
X964900Y-647800D01*
X965500Y-648200D01*
G01X973900Y-653000D02*
Y-647667D01*
G01Y-648600D02*
X973500Y-648067D01*
X972900Y-647800D01*
X972200Y-647667D01*
X971500Y-647933D01*
X970900Y-648467D01*
X970500Y-649267D01*
X970300Y-650333D01*
X970500Y-651400D01*
X970900Y-652200D01*
X971500Y-652733D01*
X972200Y-653000D01*
X972900Y-652867D01*
X973500Y-652467D01*
X973900Y-651934D01*
G01X977600Y-647667D02*
X978800Y-653000D01*
X980100Y-647667D01*
X981400Y-653000D01*
X982600Y-647667D01*
G01X988100D02*
Y-653000D01*
G01Y-645533D02*
X987900Y-645400D01*
Y-645133D01*
X988100Y-645000D01*
X988300Y-645133D01*
Y-645400D01*
X988100Y-645533D01*
G01X994400Y-653000D02*
Y-647667D01*
G01Y-649000D02*
X994800Y-648333D01*
X995400Y-647800D01*
X996200Y-647667D01*
X996900Y-647800D01*
X997500Y-648333D01*
X997800Y-649267D01*
Y-653000D01*
G01X1002700Y-655000D02*
X1003400Y-655533D01*
X1004200Y-655667D01*
X1004900Y-655533D01*
X1005500Y-654867D01*
X1005900Y-653933D01*
Y-647667D01*
G01Y-648733D02*
X1005500Y-648200D01*
X1004900Y-647800D01*
X1004200Y-647667D01*
X1003400Y-647933D01*
X1002900Y-648467D01*
X1002500Y-649400D01*
X1002300Y-650333D01*
X1002400Y-651133D01*
X1002800Y-652067D01*
X1003400Y-652733D01*
X1004200Y-653000D01*
X1004800Y-652867D01*
X1005500Y-652333D01*
X1005900Y-651800D01*
G01X1021900Y-653000D02*
Y-647667D01*
G01Y-648600D02*
X1021500Y-648067D01*
X1020900Y-647800D01*
X1020200Y-647667D01*
X1019500Y-647933D01*
X1018900Y-648467D01*
X1018500Y-649267D01*
X1018300Y-650333D01*
X1018500Y-651400D01*
X1018900Y-652200D01*
X1019500Y-652733D01*
X1020200Y-653000D01*
X1020900Y-652867D01*
X1021500Y-652467D01*
X1021900Y-651934D01*
G01X1026400Y-653000D02*
Y-647667D01*
G01Y-649000D02*
X1026800Y-648333D01*
X1027400Y-647800D01*
X1028200Y-647667D01*
X1028900Y-647800D01*
X1029500Y-648333D01*
X1029800Y-649267D01*
Y-653000D01*
G01X1037900Y-645000D02*
Y-653000D01*
G01Y-651800D02*
X1037500Y-652467D01*
X1036900Y-652867D01*
X1036200Y-653000D01*
X1035400Y-652733D01*
X1034800Y-652067D01*
X1034400Y-651267D01*
X1034300Y-650333D01*
X1034400Y-649400D01*
X1034800Y-648600D01*
X1035400Y-647933D01*
X1036200Y-647667D01*
X1036900Y-647800D01*
X1037400Y-648067D01*
X1037900Y-648600D01*
G01X1050400Y-653000D02*
Y-645000D01*
G01Y-648867D02*
X1050900Y-648200D01*
X1051400Y-647800D01*
X1052200Y-647667D01*
X1052800Y-647800D01*
X1053500Y-648333D01*
X1053800Y-649133D01*
Y-653000D01*
G01X1060100D02*
X1059500Y-652867D01*
X1058900Y-652333D01*
X1058500Y-651400D01*
X1058300Y-650333D01*
X1058500Y-649267D01*
X1058900Y-648333D01*
X1059500Y-647800D01*
X1060100Y-647667D01*
X1060700Y-647800D01*
X1061300Y-648333D01*
X1061700Y-649267D01*
X1061800Y-650333D01*
X1061700Y-651400D01*
X1061300Y-652333D01*
X1060700Y-652867D01*
X1060100Y-653000D01*
G01X1068100D02*
Y-645000D01*
G01X1074600Y-649400D02*
X1077800D01*
X1077500Y-648467D01*
X1077000Y-647933D01*
X1076300Y-647667D01*
X1075600Y-647800D01*
X1075000Y-648200D01*
X1074600Y-649133D01*
X1074400Y-649934D01*
Y-650733D01*
X1074600Y-651533D01*
X1075100Y-652333D01*
X1075700Y-652867D01*
X1076400Y-653000D01*
X1077100Y-652733D01*
X1077800Y-651934D01*
G01X1089900Y-653000D02*
Y-645000D01*
X1091900D01*
X1092700Y-645400D01*
X1093300Y-645933D01*
X1093800Y-646733D01*
X1094200Y-647667D01*
X1094300Y-649000D01*
X1094200Y-650333D01*
X1093800Y-651267D01*
X1093300Y-652067D01*
X1092700Y-652600D01*
X1091900Y-653000D01*
X1089900D01*
G01X1100100Y-647667D02*
Y-653000D01*
G01Y-645533D02*
X1099900Y-645400D01*
Y-645133D01*
X1100100Y-645000D01*
X1100300Y-645133D01*
Y-645400D01*
X1100100Y-645533D01*
G01X1109900Y-653000D02*
Y-647667D01*
G01Y-648600D02*
X1109500Y-648067D01*
X1108900Y-647800D01*
X1108200Y-647667D01*
X1107500Y-647933D01*
X1106900Y-648467D01*
X1106500Y-649267D01*
X1106300Y-650333D01*
X1106500Y-651400D01*
X1106900Y-652200D01*
X1107500Y-652733D01*
X1108200Y-653000D01*
X1108900Y-652867D01*
X1109500Y-652467D01*
X1109900Y-651934D01*
G01X1116100Y-653267D02*
X1115900Y-653133D01*
Y-652867D01*
X1116100Y-652733D01*
X1116300Y-652867D01*
Y-653133D01*
X1116100Y-653267D01*
G01X1132100Y-653000D02*
Y-645000D01*
X1130900Y-646600D01*
G01Y-653000D02*
X1133300D01*
G01X1138200Y-646333D02*
X1138800Y-645533D01*
X1139500Y-645133D01*
X1140300Y-645000D01*
X1141300Y-645267D01*
X1142000Y-645933D01*
X1142200Y-646733D01*
X1142100Y-647534D01*
X1141700Y-648200D01*
X1139700Y-649533D01*
X1138800Y-650467D01*
X1138200Y-651800D01*
X1138000Y-653000D01*
X1142200D01*
G01X1146200Y-649667D02*
X1146900Y-648733D01*
X1147500Y-648200D01*
X1148300Y-647933D01*
X1149000Y-648200D01*
X1149500Y-648733D01*
X1149900Y-649533D01*
X1150000Y-650467D01*
X1149900Y-651267D01*
X1149500Y-652067D01*
X1148900Y-652733D01*
X1148200Y-653000D01*
X1147400Y-652733D01*
X1146700Y-651934D01*
X1146300Y-650733D01*
X1146200Y-649400D01*
X1146400Y-647667D01*
X1146700Y-646733D01*
X1147200Y-645800D01*
X1147900Y-645133D01*
X1148600Y-645000D01*
X1149300Y-645267D01*
X1149800Y-645933D01*
G01X1153100Y-653000D02*
Y-647667D01*
G01Y-649133D02*
X1153400Y-648467D01*
X1153900Y-647933D01*
X1154600Y-647667D01*
X1155300Y-647933D01*
X1155800Y-648467D01*
X1156100Y-649133D01*
Y-653000D01*
G01Y-649133D02*
X1156400Y-648467D01*
X1156900Y-647933D01*
X1157600Y-647667D01*
X1158300Y-647933D01*
X1158800Y-648467D01*
X1159100Y-649267D01*
Y-653000D01*
G01X1164100Y-647667D02*
Y-653000D01*
G01Y-645533D02*
X1163900Y-645400D01*
Y-645133D01*
X1164100Y-645000D01*
X1164300Y-645133D01*
Y-645400D01*
X1164100Y-645533D01*
G01X1172100Y-653000D02*
Y-645000D01*
G01X1188100Y-647667D02*
Y-653000D01*
G01Y-645533D02*
X1187900Y-645400D01*
Y-645133D01*
X1188100Y-645000D01*
X1188300Y-645133D01*
Y-645400D01*
X1188100Y-645533D01*
G01X1194600Y-652067D02*
X1195100Y-652600D01*
X1195800Y-653000D01*
X1196400D01*
X1197000Y-652733D01*
X1197400Y-652333D01*
X1197600Y-651800D01*
X1197500Y-651000D01*
X1197100Y-650600D01*
X1195300Y-649800D01*
X1194900Y-648867D01*
X1195100Y-648200D01*
X1195500Y-647800D01*
X1196100Y-647667D01*
X1196700Y-647800D01*
X1197300Y-648200D01*
G01X1209100Y-653000D02*
Y-647667D01*
G01Y-649133D02*
X1209400Y-648467D01*
X1209900Y-647933D01*
X1210600Y-647667D01*
X1211300Y-647933D01*
X1211800Y-648467D01*
X1212100Y-649133D01*
Y-653000D01*
G01Y-649133D02*
X1212400Y-648467D01*
X1212900Y-647933D01*
X1213600Y-647667D01*
X1214300Y-647933D01*
X1214800Y-648467D01*
X1215100Y-649267D01*
Y-653000D01*
G01X1221900D02*
Y-647667D01*
G01Y-648600D02*
X1221500Y-648067D01*
X1220900Y-647800D01*
X1220200Y-647667D01*
X1219500Y-647933D01*
X1218900Y-648467D01*
X1218500Y-649267D01*
X1218300Y-650333D01*
X1218500Y-651400D01*
X1218900Y-652200D01*
X1219500Y-652733D01*
X1220200Y-653000D01*
X1220900Y-652867D01*
X1221500Y-652467D01*
X1221900Y-651934D01*
G01X1226700Y-653000D02*
Y-647667D01*
G01Y-648733D02*
X1227200Y-648200D01*
X1227700Y-647800D01*
X1228400Y-647667D01*
X1228900Y-647800D01*
X1229500Y-648200D01*
G01X1234400Y-653000D02*
Y-645000D01*
G01X1237600Y-647667D02*
X1234400Y-650733D01*
G01X1235700Y-649533D02*
X1237800Y-653000D01*
G01X1242600Y-649400D02*
X1245800D01*
X1245500Y-648467D01*
X1245000Y-647933D01*
X1244300Y-647667D01*
X1243600Y-647800D01*
X1243000Y-648200D01*
X1242600Y-649133D01*
X1242400Y-649934D01*
Y-650733D01*
X1242600Y-651533D01*
X1243100Y-652333D01*
X1243700Y-652867D01*
X1244400Y-653000D01*
X1245100Y-652733D01*
X1245800Y-651934D01*
G01X1253900Y-645000D02*
Y-653000D01*
G01Y-651800D02*
X1253500Y-652467D01*
X1252900Y-652867D01*
X1252200Y-653000D01*
X1251400Y-652733D01*
X1250800Y-652067D01*
X1250400Y-651267D01*
X1250300Y-650333D01*
X1250400Y-649400D01*
X1250800Y-648600D01*
X1251400Y-647933D01*
X1252200Y-647667D01*
X1252900Y-647800D01*
X1253400Y-648067D01*
X1253900Y-648600D01*
G01X1268100Y-647667D02*
Y-653000D01*
G01Y-645533D02*
X1267900Y-645400D01*
Y-645133D01*
X1268100Y-645000D01*
X1268300Y-645133D01*
Y-645400D01*
X1268100Y-645533D01*
G01X1274400Y-653000D02*
Y-647667D01*
G01Y-649000D02*
X1274800Y-648333D01*
X1275400Y-647800D01*
X1276200Y-647667D01*
X1276900Y-647800D01*
X1277500Y-648333D01*
X1277800Y-649267D01*
Y-653000D01*
G01X1292700Y-649000D02*
X1294700D01*
Y-651400D01*
X1294100Y-652200D01*
X1293400Y-652733D01*
X1292400Y-653000D01*
X1291400Y-652733D01*
X1290700Y-652200D01*
X1290100Y-651400D01*
X1289700Y-650467D01*
X1289500Y-649400D01*
Y-648467D01*
X1289700Y-647667D01*
X1290100Y-646733D01*
X1290700Y-645933D01*
X1291300Y-645400D01*
X1292100Y-645000D01*
X1292800D01*
X1293600Y-645267D01*
X1294200Y-645800D01*
G01X1298600Y-649400D02*
X1301800D01*
X1301500Y-648467D01*
X1301000Y-647933D01*
X1300300Y-647667D01*
X1299600Y-647800D01*
X1299000Y-648200D01*
X1298600Y-649133D01*
X1298400Y-649934D01*
Y-650733D01*
X1298600Y-651533D01*
X1299100Y-652333D01*
X1299700Y-652867D01*
X1300400Y-653000D01*
X1301100Y-652733D01*
X1301800Y-651934D01*
G01X1306700Y-653000D02*
Y-647667D01*
G01Y-648733D02*
X1307200Y-648200D01*
X1307700Y-647800D01*
X1308400Y-647667D01*
X1308900Y-647800D01*
X1309500Y-648200D01*
G01X1314300Y-653000D02*
Y-645000D01*
G01Y-649000D02*
X1314800Y-648200D01*
X1315400Y-647800D01*
X1316000Y-647667D01*
X1316900Y-647933D01*
X1317500Y-648467D01*
X1317900Y-649400D01*
Y-650467D01*
X1317700Y-651533D01*
X1317300Y-652333D01*
X1316600Y-652867D01*
X1316000Y-653000D01*
X1315400Y-652867D01*
X1314800Y-652467D01*
X1314300Y-651800D01*
G01X1322600Y-649400D02*
X1325800D01*
X1325500Y-648467D01*
X1325000Y-647933D01*
X1324300Y-647667D01*
X1323600Y-647800D01*
X1323000Y-648200D01*
X1322600Y-649133D01*
X1322400Y-649934D01*
Y-650733D01*
X1322600Y-651533D01*
X1323100Y-652333D01*
X1323700Y-652867D01*
X1324400Y-653000D01*
X1325100Y-652733D01*
X1325800Y-651934D01*
G01X1330700Y-653000D02*
Y-647667D01*
G01Y-648733D02*
X1331200Y-648200D01*
X1331700Y-647800D01*
X1332400Y-647667D01*
X1332900Y-647800D01*
X1333500Y-648200D01*
G01X1347500Y-653000D02*
Y-646200D01*
X1347700Y-645533D01*
X1348100Y-645133D01*
X1348700Y-645000D01*
X1349300Y-645267D01*
X1349600Y-645933D01*
G01X1348400Y-648200D02*
X1346400D01*
G01X1356100Y-647667D02*
Y-653000D01*
G01Y-645533D02*
X1355900Y-645400D01*
Y-645133D01*
X1356100Y-645000D01*
X1356300Y-645133D01*
Y-645400D01*
X1356100Y-645533D01*
G01X1364100Y-653000D02*
Y-645000D01*
G01X1370600Y-649400D02*
X1373800D01*
X1373500Y-648467D01*
X1373000Y-647933D01*
X1372300Y-647667D01*
X1371600Y-647800D01*
X1371000Y-648200D01*
X1370600Y-649133D01*
X1370400Y-649934D01*
Y-650733D01*
X1370600Y-651533D01*
X1371100Y-652333D01*
X1371700Y-652867D01*
X1372400Y-653000D01*
X1373100Y-652733D01*
X1373800Y-651934D01*
G01X1380100Y-653267D02*
X1379900Y-653133D01*
Y-652867D01*
X1380100Y-652733D01*
X1380300Y-652867D01*
Y-653133D01*
X1380100Y-653267D01*
G01X530400Y-633200D02*
X532800D01*
G01X531600D02*
Y-641200D01*
G01X530400D02*
X532800D01*
G01X539000D02*
Y-634400D01*
X539200Y-633733D01*
X539600Y-633333D01*
X540200Y-633200D01*
X540800Y-633467D01*
X541100Y-634133D01*
G01X539900Y-636400D02*
X537900D01*
G01X555600Y-635867D02*
Y-641200D01*
G01Y-633733D02*
X555400Y-633600D01*
Y-633333D01*
X555600Y-633200D01*
X555800Y-633333D01*
Y-633600D01*
X555600Y-633733D01*
G01X562100Y-640267D02*
X562600Y-640800D01*
X563300Y-641200D01*
X563900D01*
X564500Y-640933D01*
X564900Y-640533D01*
X565100Y-640000D01*
X565000Y-639200D01*
X564600Y-638800D01*
X562800Y-638000D01*
X562400Y-637067D01*
X562600Y-636400D01*
X563000Y-636000D01*
X563600Y-635867D01*
X564200Y-636000D01*
X564800Y-636400D01*
G01X578200Y-643200D02*
X578900Y-643733D01*
X579700Y-643867D01*
X580400Y-643733D01*
X581000Y-643067D01*
X581400Y-642133D01*
Y-635867D01*
G01Y-636933D02*
X581000Y-636400D01*
X580400Y-636000D01*
X579700Y-635867D01*
X578900Y-636133D01*
X578400Y-636667D01*
X578000Y-637600D01*
X577800Y-638533D01*
X577900Y-639333D01*
X578300Y-640267D01*
X578900Y-640933D01*
X579700Y-641200D01*
X580300Y-641067D01*
X581000Y-640533D01*
X581400Y-640000D01*
G01X586200Y-641200D02*
Y-635867D01*
G01Y-636933D02*
X586700Y-636400D01*
X587200Y-636000D01*
X587900Y-635867D01*
X588400Y-636000D01*
X589000Y-636400D01*
G01X594100Y-637600D02*
X597300D01*
X597000Y-636667D01*
X596500Y-636133D01*
X595800Y-635867D01*
X595100Y-636000D01*
X594500Y-636400D01*
X594100Y-637333D01*
X593900Y-638134D01*
Y-638933D01*
X594100Y-639733D01*
X594600Y-640533D01*
X595200Y-641067D01*
X595900Y-641200D01*
X596600Y-640933D01*
X597300Y-640134D01*
G01X605400Y-641200D02*
Y-635867D01*
G01Y-636800D02*
X605000Y-636267D01*
X604400Y-636000D01*
X603700Y-635867D01*
X603000Y-636133D01*
X602400Y-636667D01*
X602000Y-637467D01*
X601800Y-638533D01*
X602000Y-639600D01*
X602400Y-640400D01*
X603000Y-640933D01*
X603700Y-641200D01*
X604400Y-641067D01*
X605000Y-640667D01*
X605400Y-640134D01*
G01X611600Y-633200D02*
Y-641200D01*
G01X610200Y-635867D02*
X613000D01*
G01X618100Y-637600D02*
X621300D01*
X621000Y-636667D01*
X620500Y-636133D01*
X619800Y-635867D01*
X619100Y-636000D01*
X618500Y-636400D01*
X618100Y-637333D01*
X617900Y-638134D01*
Y-638933D01*
X618100Y-639733D01*
X618600Y-640533D01*
X619200Y-641067D01*
X619900Y-641200D01*
X620600Y-640933D01*
X621300Y-640134D01*
G01X626200Y-641200D02*
Y-635867D01*
G01Y-636933D02*
X626700Y-636400D01*
X627200Y-636000D01*
X627900Y-635867D01*
X628400Y-636000D01*
X629000Y-636400D01*
G01X643600Y-633200D02*
Y-641200D01*
G01X642200Y-635867D02*
X645000D01*
G01X649900Y-641200D02*
Y-633200D01*
G01Y-637067D02*
X650400Y-636400D01*
X650900Y-636000D01*
X651700Y-635867D01*
X652300Y-636000D01*
X653000Y-636533D01*
X653300Y-637333D01*
Y-641200D01*
G01X661400D02*
Y-635867D01*
G01Y-636800D02*
X661000Y-636267D01*
X660400Y-636000D01*
X659700Y-635867D01*
X659000Y-636133D01*
X658400Y-636667D01*
X658000Y-637467D01*
X657800Y-638533D01*
X658000Y-639600D01*
X658400Y-640400D01*
X659000Y-640933D01*
X659700Y-641200D01*
X660400Y-641067D01*
X661000Y-640667D01*
X661400Y-640134D01*
G01X665900Y-641200D02*
Y-635867D01*
G01Y-637200D02*
X666300Y-636533D01*
X666900Y-636000D01*
X667700Y-635867D01*
X668400Y-636000D01*
X669000Y-636533D01*
X669300Y-637467D01*
Y-641200D01*
G01X683600D02*
Y-633200D01*
X682400Y-634800D01*
G01Y-641200D02*
X684800D01*
G01X696600D02*
Y-635867D01*
G01Y-637333D02*
X696900Y-636667D01*
X697400Y-636133D01*
X698100Y-635867D01*
X698800Y-636133D01*
X699300Y-636667D01*
X699600Y-637333D01*
Y-641200D01*
G01Y-637333D02*
X699900Y-636667D01*
X700400Y-636133D01*
X701100Y-635867D01*
X701800Y-636133D01*
X702300Y-636667D01*
X702600Y-637467D01*
Y-641200D01*
G01X707600Y-635867D02*
Y-641200D01*
G01Y-633733D02*
X707400Y-633600D01*
Y-633333D01*
X707600Y-633200D01*
X707800Y-633333D01*
Y-633600D01*
X707600Y-633733D01*
G01X714100Y-640267D02*
X714600Y-640800D01*
X715300Y-641200D01*
X715900D01*
X716500Y-640933D01*
X716900Y-640533D01*
X717100Y-640000D01*
X717000Y-639200D01*
X716600Y-638800D01*
X714800Y-638000D01*
X714400Y-637067D01*
X714600Y-636400D01*
X715000Y-636000D01*
X715600Y-635867D01*
X716200Y-636000D01*
X716800Y-636400D01*
G01X723400Y-642667D02*
X723800Y-640933D01*
G01X737800Y-643867D02*
Y-635867D01*
G01Y-637067D02*
X738300Y-636400D01*
X738800Y-636000D01*
X739600Y-635867D01*
X740300Y-636000D01*
X741000Y-636667D01*
X741300Y-637600D01*
X741400Y-638533D01*
X741300Y-639467D01*
X741000Y-640400D01*
X740400Y-640933D01*
X739600Y-641200D01*
X738900Y-641067D01*
X738200Y-640667D01*
X737800Y-640134D01*
G01X747600Y-641200D02*
Y-633200D01*
G01X754100Y-637600D02*
X757300D01*
X757000Y-636667D01*
X756500Y-636133D01*
X755800Y-635867D01*
X755100Y-636000D01*
X754500Y-636400D01*
X754100Y-637333D01*
X753900Y-638134D01*
Y-638933D01*
X754100Y-639733D01*
X754600Y-640533D01*
X755200Y-641067D01*
X755900Y-641200D01*
X756600Y-640933D01*
X757300Y-640134D01*
G01X765400Y-641200D02*
Y-635867D01*
G01Y-636800D02*
X765000Y-636267D01*
X764400Y-636000D01*
X763700Y-635867D01*
X763000Y-636133D01*
X762400Y-636667D01*
X762000Y-637467D01*
X761800Y-638533D01*
X762000Y-639600D01*
X762400Y-640400D01*
X763000Y-640933D01*
X763700Y-641200D01*
X764400Y-641067D01*
X765000Y-640667D01*
X765400Y-640134D01*
G01X770100Y-640267D02*
X770600Y-640800D01*
X771300Y-641200D01*
X771900D01*
X772500Y-640933D01*
X772900Y-640533D01*
X773100Y-640000D01*
X773000Y-639200D01*
X772600Y-638800D01*
X770800Y-638000D01*
X770400Y-637067D01*
X770600Y-636400D01*
X771000Y-636000D01*
X771600Y-635867D01*
X772200Y-636000D01*
X772800Y-636400D01*
G01X778100Y-637600D02*
X781300D01*
X781000Y-636667D01*
X780500Y-636133D01*
X779800Y-635867D01*
X779100Y-636000D01*
X778500Y-636400D01*
X778100Y-637333D01*
X777900Y-638134D01*
Y-638933D01*
X778100Y-639733D01*
X778600Y-640533D01*
X779200Y-641067D01*
X779900Y-641200D01*
X780600Y-640933D01*
X781300Y-640134D01*
G01X795600Y-635867D02*
Y-641200D01*
G01Y-633733D02*
X795400Y-633600D01*
Y-633333D01*
X795600Y-633200D01*
X795800Y-633333D01*
Y-633600D01*
X795600Y-633733D01*
G01X802100Y-640267D02*
X802600Y-640800D01*
X803300Y-641200D01*
X803900D01*
X804500Y-640933D01*
X804900Y-640533D01*
X805100Y-640000D01*
X805000Y-639200D01*
X804600Y-638800D01*
X802800Y-638000D01*
X802400Y-637067D01*
X802600Y-636400D01*
X803000Y-636000D01*
X803600Y-635867D01*
X804200Y-636000D01*
X804800Y-636400D01*
G01X810100Y-640267D02*
X810600Y-640800D01*
X811300Y-641200D01*
X811900D01*
X812500Y-640933D01*
X812900Y-640533D01*
X813100Y-640000D01*
X813000Y-639200D01*
X812600Y-638800D01*
X810800Y-638000D01*
X810400Y-637067D01*
X810600Y-636400D01*
X811000Y-636000D01*
X811600Y-635867D01*
X812200Y-636000D01*
X812800Y-636400D01*
G01X817900Y-635867D02*
Y-639600D01*
X818300Y-640533D01*
X818900Y-641067D01*
X819600Y-641200D01*
X820300Y-641067D01*
X820900Y-640533D01*
X821300Y-639600D01*
G01Y-641200D02*
Y-635867D01*
G01X826100Y-637600D02*
X829300D01*
X829000Y-636667D01*
X828500Y-636133D01*
X827800Y-635867D01*
X827100Y-636000D01*
X826500Y-636400D01*
X826100Y-637333D01*
X825900Y-638134D01*
Y-638933D01*
X826100Y-639733D01*
X826600Y-640533D01*
X827200Y-641067D01*
X827900Y-641200D01*
X828600Y-640933D01*
X829300Y-640134D01*
G01X842100Y-637600D02*
X845300D01*
X845000Y-636667D01*
X844500Y-636133D01*
X843800Y-635867D01*
X843100Y-636000D01*
X842500Y-636400D01*
X842100Y-637333D01*
X841900Y-638134D01*
Y-638933D01*
X842100Y-639733D01*
X842600Y-640533D01*
X843200Y-641067D01*
X843900Y-641200D01*
X844600Y-640933D01*
X845300Y-640134D01*
G01X849900Y-641200D02*
Y-635867D01*
G01Y-637200D02*
X850300Y-636533D01*
X850900Y-636000D01*
X851700Y-635867D01*
X852400Y-636000D01*
X853000Y-636533D01*
X853300Y-637467D01*
Y-641200D01*
G01X858200Y-643200D02*
X858900Y-643733D01*
X859700Y-643867D01*
X860400Y-643733D01*
X861000Y-643067D01*
X861400Y-642133D01*
Y-635867D01*
G01Y-636933D02*
X861000Y-636400D01*
X860400Y-636000D01*
X859700Y-635867D01*
X858900Y-636133D01*
X858400Y-636667D01*
X858000Y-637600D01*
X857800Y-638533D01*
X857900Y-639333D01*
X858300Y-640267D01*
X858900Y-640933D01*
X859700Y-641200D01*
X860300Y-641067D01*
X861000Y-640533D01*
X861400Y-640000D01*
G01X867600Y-635867D02*
Y-641200D01*
G01Y-633733D02*
X867400Y-633600D01*
Y-633333D01*
X867600Y-633200D01*
X867800Y-633333D01*
Y-633600D01*
X867600Y-633733D01*
G01X873900Y-641200D02*
Y-635867D01*
G01Y-637200D02*
X874300Y-636533D01*
X874900Y-636000D01*
X875700Y-635867D01*
X876400Y-636000D01*
X877000Y-636533D01*
X877300Y-637467D01*
Y-641200D01*
G01X882100Y-637600D02*
X885300D01*
X885000Y-636667D01*
X884500Y-636133D01*
X883800Y-635867D01*
X883100Y-636000D01*
X882500Y-636400D01*
X882100Y-637333D01*
X881900Y-638134D01*
Y-638933D01*
X882100Y-639733D01*
X882600Y-640533D01*
X883200Y-641067D01*
X883900Y-641200D01*
X884600Y-640933D01*
X885300Y-640134D01*
G01X890100Y-637600D02*
X893300D01*
X893000Y-636667D01*
X892500Y-636133D01*
X891800Y-635867D01*
X891100Y-636000D01*
X890500Y-636400D01*
X890100Y-637333D01*
X889900Y-638134D01*
Y-638933D01*
X890100Y-639733D01*
X890600Y-640533D01*
X891200Y-641067D01*
X891900Y-641200D01*
X892600Y-640933D01*
X893300Y-640134D01*
G01X898200Y-641200D02*
Y-635867D01*
G01Y-636933D02*
X898700Y-636400D01*
X899200Y-636000D01*
X899900Y-635867D01*
X900400Y-636000D01*
X901000Y-636400D01*
G01X907600Y-635867D02*
Y-641200D01*
G01Y-633733D02*
X907400Y-633600D01*
Y-633333D01*
X907600Y-633200D01*
X907800Y-633333D01*
Y-633600D01*
X907600Y-633733D01*
G01X913900Y-641200D02*
Y-635867D01*
G01Y-637200D02*
X914300Y-636533D01*
X914900Y-636000D01*
X915700Y-635867D01*
X916400Y-636000D01*
X917000Y-636533D01*
X917300Y-637467D01*
Y-641200D01*
G01X922200Y-643200D02*
X922900Y-643733D01*
X923700Y-643867D01*
X924400Y-643733D01*
X925000Y-643067D01*
X925400Y-642133D01*
Y-635867D01*
G01Y-636933D02*
X925000Y-636400D01*
X924400Y-636000D01*
X923700Y-635867D01*
X922900Y-636133D01*
X922400Y-636667D01*
X922000Y-637600D01*
X921800Y-638533D01*
X921900Y-639333D01*
X922300Y-640267D01*
X922900Y-640933D01*
X923700Y-641200D01*
X924300Y-641067D01*
X925000Y-640533D01*
X925400Y-640000D01*
G01X941400Y-643867D02*
Y-635867D01*
G01Y-637067D02*
X940900Y-636400D01*
X940300Y-636000D01*
X939600Y-635867D01*
X939000Y-636000D01*
X938300Y-636667D01*
X937900Y-637600D01*
X937800Y-638533D01*
X937900Y-639467D01*
X938300Y-640400D01*
X939000Y-641067D01*
X939600Y-641200D01*
X940300Y-641067D01*
X940900Y-640667D01*
X941400Y-640000D01*
G01X945900Y-635867D02*
Y-639600D01*
X946300Y-640533D01*
X946900Y-641067D01*
X947600Y-641200D01*
X948300Y-641067D01*
X948900Y-640533D01*
X949300Y-639600D01*
G01Y-641200D02*
Y-635867D01*
G01X954100Y-637600D02*
X957300D01*
X957000Y-636667D01*
X956500Y-636133D01*
X955800Y-635867D01*
X955100Y-636000D01*
X954500Y-636400D01*
X954100Y-637333D01*
X953900Y-638134D01*
Y-638933D01*
X954100Y-639733D01*
X954600Y-640533D01*
X955200Y-641067D01*
X955900Y-641200D01*
X956600Y-640933D01*
X957300Y-640134D01*
G01X962200Y-641200D02*
Y-635867D01*
G01Y-636933D02*
X962700Y-636400D01*
X963200Y-636000D01*
X963900Y-635867D01*
X964400Y-636000D01*
X965000Y-636400D01*
G01X969500Y-643600D02*
X970100Y-643867D01*
X970900Y-643600D01*
X971400Y-643067D01*
X971800Y-642400D01*
X972400Y-640267D01*
X973700Y-635867D01*
G01X970500D02*
X972400Y-640267D01*
G01X979600Y-641467D02*
X979400Y-641333D01*
Y-641067D01*
X979600Y-640933D01*
X979800Y-641067D01*
Y-641333D01*
X979600Y-641467D01*
G01X530200Y-620900D02*
Y-626633D01*
X530600Y-627834D01*
X531400Y-628633D01*
X532400Y-628900D01*
X533400Y-628633D01*
X534200Y-627834D01*
X534600Y-626633D01*
Y-620900D01*
G01X538700Y-628900D02*
Y-623567D01*
G01Y-624900D02*
X539100Y-624233D01*
X539700Y-623700D01*
X540500Y-623567D01*
X541200Y-623700D01*
X541800Y-624233D01*
X542100Y-625167D01*
Y-628900D01*
G01X548400Y-623567D02*
Y-628900D01*
G01Y-621433D02*
X548200Y-621300D01*
Y-621033D01*
X548400Y-620900D01*
X548600Y-621033D01*
Y-621300D01*
X548400Y-621433D01*
G01X556400Y-620900D02*
Y-628900D01*
G01X555000Y-623567D02*
X557800D01*
G01X574000Y-624233D02*
X573300Y-623700D01*
X572700Y-623567D01*
X571900Y-623833D01*
X571300Y-624367D01*
X570900Y-625300D01*
X570800Y-626233D01*
X570900Y-627167D01*
X571300Y-627967D01*
X571900Y-628633D01*
X572700Y-628900D01*
X573400Y-628633D01*
X574000Y-628100D01*
G01X580400Y-628900D02*
X579800Y-628767D01*
X579200Y-628233D01*
X578800Y-627300D01*
X578600Y-626233D01*
X578800Y-625167D01*
X579200Y-624233D01*
X579800Y-623700D01*
X580400Y-623567D01*
X581000Y-623700D01*
X581600Y-624233D01*
X582000Y-625167D01*
X582100Y-626233D01*
X582000Y-627300D01*
X581600Y-628233D01*
X581000Y-628767D01*
X580400Y-628900D01*
G01X586700D02*
Y-623567D01*
G01Y-624900D02*
X587100Y-624233D01*
X587700Y-623700D01*
X588500Y-623567D01*
X589200Y-623700D01*
X589800Y-624233D01*
X590100Y-625167D01*
Y-628900D01*
G01X594600Y-623567D02*
X596400Y-628900D01*
X598200Y-623567D01*
G01X602900Y-625300D02*
X606100D01*
X605800Y-624367D01*
X605300Y-623833D01*
X604600Y-623567D01*
X603900Y-623700D01*
X603300Y-624100D01*
X602900Y-625033D01*
X602700Y-625834D01*
Y-626633D01*
X602900Y-627433D01*
X603400Y-628233D01*
X604000Y-628767D01*
X604700Y-628900D01*
X605400Y-628633D01*
X606100Y-627834D01*
G01X611000Y-628900D02*
Y-623567D01*
G01Y-624633D02*
X611500Y-624100D01*
X612000Y-623700D01*
X612700Y-623567D01*
X613200Y-623700D01*
X613800Y-624100D01*
G01X618900Y-627967D02*
X619400Y-628500D01*
X620100Y-628900D01*
X620700D01*
X621300Y-628633D01*
X621700Y-628233D01*
X621900Y-627700D01*
X621800Y-626900D01*
X621400Y-626500D01*
X619600Y-625700D01*
X619200Y-624767D01*
X619400Y-624100D01*
X619800Y-623700D01*
X620400Y-623567D01*
X621000Y-623700D01*
X621600Y-624100D01*
G01X628400Y-623567D02*
Y-628900D01*
G01Y-621433D02*
X628200Y-621300D01*
Y-621033D01*
X628400Y-620900D01*
X628600Y-621033D01*
Y-621300D01*
X628400Y-621433D01*
G01X636400Y-628900D02*
X635800Y-628767D01*
X635200Y-628233D01*
X634800Y-627300D01*
X634600Y-626233D01*
X634800Y-625167D01*
X635200Y-624233D01*
X635800Y-623700D01*
X636400Y-623567D01*
X637000Y-623700D01*
X637600Y-624233D01*
X638000Y-625167D01*
X638100Y-626233D01*
X638000Y-627300D01*
X637600Y-628233D01*
X637000Y-628767D01*
X636400Y-628900D01*
G01X642700D02*
Y-623567D01*
G01Y-624900D02*
X643100Y-624233D01*
X643700Y-623700D01*
X644500Y-623567D01*
X645200Y-623700D01*
X645800Y-624233D01*
X646100Y-625167D01*
Y-628900D01*
G01X658900Y-625300D02*
X662100D01*
X661800Y-624367D01*
X661300Y-623833D01*
X660600Y-623567D01*
X659900Y-623700D01*
X659300Y-624100D01*
X658900Y-625033D01*
X658700Y-625834D01*
Y-626633D01*
X658900Y-627433D01*
X659400Y-628233D01*
X660000Y-628767D01*
X660700Y-628900D01*
X661400Y-628633D01*
X662100Y-627834D01*
G01X667000Y-628900D02*
Y-623567D01*
G01Y-624633D02*
X667500Y-624100D01*
X668000Y-623700D01*
X668700Y-623567D01*
X669200Y-623700D01*
X669800Y-624100D01*
G01X675000Y-628900D02*
Y-623567D01*
G01Y-624633D02*
X675500Y-624100D01*
X676000Y-623700D01*
X676700Y-623567D01*
X677200Y-623700D01*
X677800Y-624100D01*
G01X684400Y-628900D02*
X683800Y-628767D01*
X683200Y-628233D01*
X682800Y-627300D01*
X682600Y-626233D01*
X682800Y-625167D01*
X683200Y-624233D01*
X683800Y-623700D01*
X684400Y-623567D01*
X685000Y-623700D01*
X685600Y-624233D01*
X686000Y-625167D01*
X686100Y-626233D01*
X686000Y-627300D01*
X685600Y-628233D01*
X685000Y-628767D01*
X684400Y-628900D01*
G01X691000D02*
Y-623567D01*
G01Y-624633D02*
X691500Y-624100D01*
X692000Y-623700D01*
X692700Y-623567D01*
X693200Y-623700D01*
X693800Y-624100D01*
G01X706600Y-628900D02*
Y-620900D01*
G01Y-624900D02*
X707100Y-624100D01*
X707700Y-623700D01*
X708300Y-623567D01*
X709200Y-623833D01*
X709800Y-624367D01*
X710200Y-625300D01*
Y-626367D01*
X710000Y-627433D01*
X709600Y-628233D01*
X708900Y-628767D01*
X708300Y-628900D01*
X707700Y-628767D01*
X707100Y-628367D01*
X706600Y-627700D01*
G01X714900Y-625300D02*
X718100D01*
X717800Y-624367D01*
X717300Y-623833D01*
X716600Y-623567D01*
X715900Y-623700D01*
X715300Y-624100D01*
X714900Y-625033D01*
X714700Y-625834D01*
Y-626633D01*
X714900Y-627433D01*
X715400Y-628233D01*
X716000Y-628767D01*
X716700Y-628900D01*
X717400Y-628633D01*
X718100Y-627834D01*
G01X724400Y-620900D02*
Y-628900D01*
G01X723000Y-623567D02*
X725800D01*
G01X729900D02*
X731100Y-628900D01*
X732400Y-623567D01*
X733700Y-628900D01*
X734900Y-623567D01*
G01X738900Y-625300D02*
X742100D01*
X741800Y-624367D01*
X741300Y-623833D01*
X740600Y-623567D01*
X739900Y-623700D01*
X739300Y-624100D01*
X738900Y-625033D01*
X738700Y-625834D01*
Y-626633D01*
X738900Y-627433D01*
X739400Y-628233D01*
X740000Y-628767D01*
X740700Y-628900D01*
X741400Y-628633D01*
X742100Y-627834D01*
G01X746900Y-625300D02*
X750100D01*
X749800Y-624367D01*
X749300Y-623833D01*
X748600Y-623567D01*
X747900Y-623700D01*
X747300Y-624100D01*
X746900Y-625033D01*
X746700Y-625834D01*
Y-626633D01*
X746900Y-627433D01*
X747400Y-628233D01*
X748000Y-628767D01*
X748700Y-628900D01*
X749400Y-628633D01*
X750100Y-627834D01*
G01X754700Y-628900D02*
Y-623567D01*
G01Y-624900D02*
X755100Y-624233D01*
X755700Y-623700D01*
X756500Y-623567D01*
X757200Y-623700D01*
X757800Y-624233D01*
X758100Y-625167D01*
Y-628900D01*
G01X769400D02*
Y-623567D01*
G01Y-625033D02*
X769700Y-624367D01*
X770200Y-623833D01*
X770900Y-623567D01*
X771600Y-623833D01*
X772100Y-624367D01*
X772400Y-625033D01*
Y-628900D01*
G01Y-625033D02*
X772700Y-624367D01*
X773200Y-623833D01*
X773900Y-623567D01*
X774600Y-623833D01*
X775100Y-624367D01*
X775400Y-625167D01*
Y-628900D01*
G01X778900Y-625300D02*
X782100D01*
X781800Y-624367D01*
X781300Y-623833D01*
X780600Y-623567D01*
X779900Y-623700D01*
X779300Y-624100D01*
X778900Y-625033D01*
X778700Y-625834D01*
Y-626633D01*
X778900Y-627433D01*
X779400Y-628233D01*
X780000Y-628767D01*
X780700Y-628900D01*
X781400Y-628633D01*
X782100Y-627834D01*
G01X788400Y-620900D02*
Y-628900D01*
G01X787000Y-623567D02*
X789800D01*
G01X795000Y-628900D02*
Y-623567D01*
G01Y-624633D02*
X795500Y-624100D01*
X796000Y-623700D01*
X796700Y-623567D01*
X797200Y-623700D01*
X797800Y-624100D01*
G01X804400Y-623567D02*
Y-628900D01*
G01Y-621433D02*
X804200Y-621300D01*
Y-621033D01*
X804400Y-620900D01*
X804600Y-621033D01*
Y-621300D01*
X804400Y-621433D01*
G01X814000Y-624233D02*
X813300Y-623700D01*
X812700Y-623567D01*
X811900Y-623833D01*
X811300Y-624367D01*
X810900Y-625300D01*
X810800Y-626233D01*
X810900Y-627167D01*
X811300Y-627967D01*
X811900Y-628633D01*
X812700Y-628900D01*
X813400Y-628633D01*
X814000Y-628100D01*
G01X830200Y-628900D02*
Y-623567D01*
G01Y-624500D02*
X829800Y-623967D01*
X829200Y-623700D01*
X828500Y-623567D01*
X827800Y-623833D01*
X827200Y-624367D01*
X826800Y-625167D01*
X826600Y-626233D01*
X826800Y-627300D01*
X827200Y-628100D01*
X827800Y-628633D01*
X828500Y-628900D01*
X829200Y-628767D01*
X829800Y-628367D01*
X830200Y-627834D01*
G01X834700Y-628900D02*
Y-623567D01*
G01Y-624900D02*
X835100Y-624233D01*
X835700Y-623700D01*
X836500Y-623567D01*
X837200Y-623700D01*
X837800Y-624233D01*
X838100Y-625167D01*
Y-628900D01*
G01X846200Y-620900D02*
Y-628900D01*
G01Y-627700D02*
X845800Y-628367D01*
X845200Y-628767D01*
X844500Y-628900D01*
X843700Y-628633D01*
X843100Y-627967D01*
X842700Y-627167D01*
X842600Y-626233D01*
X842700Y-625300D01*
X843100Y-624500D01*
X843700Y-623833D01*
X844500Y-623567D01*
X845200Y-623700D01*
X845700Y-623967D01*
X846200Y-624500D01*
G01X862400Y-628900D02*
X858400D01*
Y-620900D01*
X862400D01*
G01X860800Y-624767D02*
X858400D01*
G01X866700Y-628900D02*
Y-623567D01*
G01Y-624900D02*
X867100Y-624233D01*
X867700Y-623700D01*
X868500Y-623567D01*
X869200Y-623700D01*
X869800Y-624233D01*
X870100Y-625167D01*
Y-628900D01*
G01X875000Y-630900D02*
X875700Y-631433D01*
X876500Y-631567D01*
X877200Y-631433D01*
X877800Y-630767D01*
X878200Y-629833D01*
Y-623567D01*
G01Y-624633D02*
X877800Y-624100D01*
X877200Y-623700D01*
X876500Y-623567D01*
X875700Y-623833D01*
X875200Y-624367D01*
X874800Y-625300D01*
X874600Y-626233D01*
X874700Y-627033D01*
X875100Y-627967D01*
X875700Y-628633D01*
X876500Y-628900D01*
X877100Y-628767D01*
X877800Y-628233D01*
X878200Y-627700D01*
G01X884400Y-628900D02*
Y-620900D01*
G01X892400Y-623567D02*
Y-628900D01*
G01Y-621433D02*
X892200Y-621300D01*
Y-621033D01*
X892400Y-620900D01*
X892600Y-621033D01*
Y-621300D01*
X892400Y-621433D01*
G01X898900Y-627967D02*
X899400Y-628500D01*
X900100Y-628900D01*
X900700D01*
X901300Y-628633D01*
X901700Y-628233D01*
X901900Y-627700D01*
X901800Y-626900D01*
X901400Y-626500D01*
X899600Y-625700D01*
X899200Y-624767D01*
X899400Y-624100D01*
X899800Y-623700D01*
X900400Y-623567D01*
X901000Y-623700D01*
X901600Y-624100D01*
G01X906700Y-628900D02*
Y-620900D01*
G01Y-624767D02*
X907200Y-624100D01*
X907700Y-623700D01*
X908500Y-623567D01*
X909100Y-623700D01*
X909800Y-624233D01*
X910100Y-625033D01*
Y-628900D01*
G01X922900Y-627967D02*
X923400Y-628500D01*
X924100Y-628900D01*
X924700D01*
X925300Y-628633D01*
X925700Y-628233D01*
X925900Y-627700D01*
X925800Y-626900D01*
X925400Y-626500D01*
X923600Y-625700D01*
X923200Y-624767D01*
X923400Y-624100D01*
X923800Y-623700D01*
X924400Y-623567D01*
X925000Y-623700D01*
X925600Y-624100D01*
G01X930300Y-631300D02*
X930900Y-631567D01*
X931700Y-631300D01*
X932200Y-630767D01*
X932600Y-630100D01*
X933200Y-627967D01*
X934500Y-623567D01*
G01X931300D02*
X933200Y-627967D01*
G01X938900D02*
X939400Y-628500D01*
X940100Y-628900D01*
X940700D01*
X941300Y-628633D01*
X941700Y-628233D01*
X941900Y-627700D01*
X941800Y-626900D01*
X941400Y-626500D01*
X939600Y-625700D01*
X939200Y-624767D01*
X939400Y-624100D01*
X939800Y-623700D01*
X940400Y-623567D01*
X941000Y-623700D01*
X941600Y-624100D01*
G01X948400Y-620900D02*
Y-628900D01*
G01X947000Y-623567D02*
X949800D01*
G01X954900Y-625300D02*
X958100D01*
X957800Y-624367D01*
X957300Y-623833D01*
X956600Y-623567D01*
X955900Y-623700D01*
X955300Y-624100D01*
X954900Y-625033D01*
X954700Y-625834D01*
Y-626633D01*
X954900Y-627433D01*
X955400Y-628233D01*
X956000Y-628767D01*
X956700Y-628900D01*
X957400Y-628633D01*
X958100Y-627834D01*
G01X961400Y-628900D02*
Y-623567D01*
G01Y-625033D02*
X961700Y-624367D01*
X962200Y-623833D01*
X962900Y-623567D01*
X963600Y-623833D01*
X964100Y-624367D01*
X964400Y-625033D01*
Y-628900D01*
G01Y-625033D02*
X964700Y-624367D01*
X965200Y-623833D01*
X965900Y-623567D01*
X966600Y-623833D01*
X967100Y-624367D01*
X967400Y-625167D01*
Y-628900D01*
G01X980400Y-623567D02*
Y-628900D01*
G01Y-621433D02*
X980200Y-621300D01*
Y-621033D01*
X980400Y-620900D01*
X980600Y-621033D01*
Y-621300D01*
X980400Y-621433D01*
G01X986900Y-627967D02*
X987400Y-628500D01*
X988100Y-628900D01*
X988700D01*
X989300Y-628633D01*
X989700Y-628233D01*
X989900Y-627700D01*
X989800Y-626900D01*
X989400Y-626500D01*
X987600Y-625700D01*
X987200Y-624767D01*
X987400Y-624100D01*
X987800Y-623700D01*
X988400Y-623567D01*
X989000Y-623700D01*
X989600Y-624100D01*
G01X1004400Y-628900D02*
Y-620900D01*
G01X1010900Y-625300D02*
X1014100D01*
X1013800Y-624367D01*
X1013300Y-623833D01*
X1012600Y-623567D01*
X1011900Y-623700D01*
X1011300Y-624100D01*
X1010900Y-625033D01*
X1010700Y-625834D01*
Y-626633D01*
X1010900Y-627433D01*
X1011400Y-628233D01*
X1012000Y-628767D01*
X1012700Y-628900D01*
X1013400Y-628633D01*
X1014100Y-627834D01*
G01X1018900Y-627967D02*
X1019400Y-628500D01*
X1020100Y-628900D01*
X1020700D01*
X1021300Y-628633D01*
X1021700Y-628233D01*
X1021900Y-627700D01*
X1021800Y-626900D01*
X1021400Y-626500D01*
X1019600Y-625700D01*
X1019200Y-624767D01*
X1019400Y-624100D01*
X1019800Y-623700D01*
X1020400Y-623567D01*
X1021000Y-623700D01*
X1021600Y-624100D01*
G01X1026900Y-627967D02*
X1027400Y-628500D01*
X1028100Y-628900D01*
X1028700D01*
X1029300Y-628633D01*
X1029700Y-628233D01*
X1029900Y-627700D01*
X1029800Y-626900D01*
X1029400Y-626500D01*
X1027600Y-625700D01*
X1027200Y-624767D01*
X1027400Y-624100D01*
X1027800Y-623700D01*
X1028400Y-623567D01*
X1029000Y-623700D01*
X1029600Y-624100D01*
G01X1044400Y-620900D02*
Y-628900D01*
G01X1043000Y-623567D02*
X1045800D01*
G01X1050700Y-628900D02*
Y-620900D01*
G01Y-624767D02*
X1051200Y-624100D01*
X1051700Y-623700D01*
X1052500Y-623567D01*
X1053100Y-623700D01*
X1053800Y-624233D01*
X1054100Y-625033D01*
Y-628900D01*
G01X1062200D02*
Y-623567D01*
G01Y-624500D02*
X1061800Y-623967D01*
X1061200Y-623700D01*
X1060500Y-623567D01*
X1059800Y-623833D01*
X1059200Y-624367D01*
X1058800Y-625167D01*
X1058600Y-626233D01*
X1058800Y-627300D01*
X1059200Y-628100D01*
X1059800Y-628633D01*
X1060500Y-628900D01*
X1061200Y-628767D01*
X1061800Y-628367D01*
X1062200Y-627834D01*
G01X1066700Y-628900D02*
Y-623567D01*
G01Y-624900D02*
X1067100Y-624233D01*
X1067700Y-623700D01*
X1068500Y-623567D01*
X1069200Y-623700D01*
X1069800Y-624233D01*
X1070100Y-625167D01*
Y-628900D01*
G01X1084400D02*
Y-620900D01*
X1083200Y-622500D01*
G01Y-628900D02*
X1085600D01*
G01X1097400D02*
Y-623567D01*
G01Y-625033D02*
X1097700Y-624367D01*
X1098200Y-623833D01*
X1098900Y-623567D01*
X1099600Y-623833D01*
X1100100Y-624367D01*
X1100400Y-625033D01*
Y-628900D01*
G01Y-625033D02*
X1100700Y-624367D01*
X1101200Y-623833D01*
X1101900Y-623567D01*
X1102600Y-623833D01*
X1103100Y-624367D01*
X1103400Y-625167D01*
Y-628900D01*
G01X1108400Y-623567D02*
Y-628900D01*
G01Y-621433D02*
X1108200Y-621300D01*
Y-621033D01*
X1108400Y-620900D01*
X1108600Y-621033D01*
Y-621300D01*
X1108400Y-621433D01*
G01X1116400Y-628900D02*
Y-620900D01*
G01X1124200Y-630367D02*
X1124600Y-628633D01*
G01X1138600Y-631567D02*
Y-623567D01*
G01Y-624767D02*
X1139100Y-624100D01*
X1139600Y-623700D01*
X1140400Y-623567D01*
X1141100Y-623700D01*
X1141800Y-624367D01*
X1142100Y-625300D01*
X1142200Y-626233D01*
X1142100Y-627167D01*
X1141800Y-628100D01*
X1141200Y-628633D01*
X1140400Y-628900D01*
X1139700Y-628767D01*
X1139000Y-628367D01*
X1138600Y-627834D01*
G01X1148400Y-628900D02*
Y-620900D01*
G01X1154900Y-625300D02*
X1158100D01*
X1157800Y-624367D01*
X1157300Y-623833D01*
X1156600Y-623567D01*
X1155900Y-623700D01*
X1155300Y-624100D01*
X1154900Y-625033D01*
X1154700Y-625834D01*
Y-626633D01*
X1154900Y-627433D01*
X1155400Y-628233D01*
X1156000Y-628767D01*
X1156700Y-628900D01*
X1157400Y-628633D01*
X1158100Y-627834D01*
G01X1166200Y-628900D02*
Y-623567D01*
G01Y-624500D02*
X1165800Y-623967D01*
X1165200Y-623700D01*
X1164500Y-623567D01*
X1163800Y-623833D01*
X1163200Y-624367D01*
X1162800Y-625167D01*
X1162600Y-626233D01*
X1162800Y-627300D01*
X1163200Y-628100D01*
X1163800Y-628633D01*
X1164500Y-628900D01*
X1165200Y-628767D01*
X1165800Y-628367D01*
X1166200Y-627834D01*
G01X1170900Y-627967D02*
X1171400Y-628500D01*
X1172100Y-628900D01*
X1172700D01*
X1173300Y-628633D01*
X1173700Y-628233D01*
X1173900Y-627700D01*
X1173800Y-626900D01*
X1173400Y-626500D01*
X1171600Y-625700D01*
X1171200Y-624767D01*
X1171400Y-624100D01*
X1171800Y-623700D01*
X1172400Y-623567D01*
X1173000Y-623700D01*
X1173600Y-624100D01*
G01X1178900Y-625300D02*
X1182100D01*
X1181800Y-624367D01*
X1181300Y-623833D01*
X1180600Y-623567D01*
X1179900Y-623700D01*
X1179300Y-624100D01*
X1178900Y-625033D01*
X1178700Y-625834D01*
Y-626633D01*
X1178900Y-627433D01*
X1179400Y-628233D01*
X1180000Y-628767D01*
X1180700Y-628900D01*
X1181400Y-628633D01*
X1182100Y-627834D01*
G01X1195800Y-628900D02*
Y-622100D01*
X1196000Y-621433D01*
X1196400Y-621033D01*
X1197000Y-620900D01*
X1197600Y-621167D01*
X1197900Y-621833D01*
G01X1196700Y-624100D02*
X1194700D01*
G01X1204400Y-628900D02*
X1203800Y-628767D01*
X1203200Y-628233D01*
X1202800Y-627300D01*
X1202600Y-626233D01*
X1202800Y-625167D01*
X1203200Y-624233D01*
X1203800Y-623700D01*
X1204400Y-623567D01*
X1205000Y-623700D01*
X1205600Y-624233D01*
X1206000Y-625167D01*
X1206100Y-626233D01*
X1206000Y-627300D01*
X1205600Y-628233D01*
X1205000Y-628767D01*
X1204400Y-628900D01*
G01X1212400D02*
Y-620900D01*
G01X1220400Y-628900D02*
Y-620900D01*
G01X1228400Y-628900D02*
X1227800Y-628767D01*
X1227200Y-628233D01*
X1226800Y-627300D01*
X1226600Y-626233D01*
X1226800Y-625167D01*
X1227200Y-624233D01*
X1227800Y-623700D01*
X1228400Y-623567D01*
X1229000Y-623700D01*
X1229600Y-624233D01*
X1230000Y-625167D01*
X1230100Y-626233D01*
X1230000Y-627300D01*
X1229600Y-628233D01*
X1229000Y-628767D01*
X1228400Y-628900D01*
G01X1233900Y-623567D02*
X1235100Y-628900D01*
X1236400Y-623567D01*
X1237700Y-628900D01*
X1238900Y-623567D01*
G01X1249400Y-628900D02*
Y-623567D01*
G01Y-625033D02*
X1249700Y-624367D01*
X1250200Y-623833D01*
X1250900Y-623567D01*
X1251600Y-623833D01*
X1252100Y-624367D01*
X1252400Y-625033D01*
Y-628900D01*
G01Y-625033D02*
X1252700Y-624367D01*
X1253200Y-623833D01*
X1253900Y-623567D01*
X1254600Y-623833D01*
X1255100Y-624367D01*
X1255400Y-625167D01*
Y-628900D01*
G01X1258900Y-625300D02*
X1262100D01*
X1261800Y-624367D01*
X1261300Y-623833D01*
X1260600Y-623567D01*
X1259900Y-623700D01*
X1259300Y-624100D01*
X1258900Y-625033D01*
X1258700Y-625834D01*
Y-626633D01*
X1258900Y-627433D01*
X1259400Y-628233D01*
X1260000Y-628767D01*
X1260700Y-628900D01*
X1261400Y-628633D01*
X1262100Y-627834D01*
G01X1270000Y-624233D02*
X1269300Y-623700D01*
X1268700Y-623567D01*
X1267900Y-623833D01*
X1267300Y-624367D01*
X1266900Y-625300D01*
X1266800Y-626233D01*
X1266900Y-627167D01*
X1267300Y-627967D01*
X1267900Y-628633D01*
X1268700Y-628900D01*
X1269400Y-628633D01*
X1270000Y-628100D01*
G01X1274700Y-628900D02*
Y-620900D01*
G01Y-624767D02*
X1275200Y-624100D01*
X1275700Y-623700D01*
X1276500Y-623567D01*
X1277100Y-623700D01*
X1277800Y-624233D01*
X1278100Y-625033D01*
Y-628900D01*
G01X1286200D02*
Y-623567D01*
G01Y-624500D02*
X1285800Y-623967D01*
X1285200Y-623700D01*
X1284500Y-623567D01*
X1283800Y-623833D01*
X1283200Y-624367D01*
X1282800Y-625167D01*
X1282600Y-626233D01*
X1282800Y-627300D01*
X1283200Y-628100D01*
X1283800Y-628633D01*
X1284500Y-628900D01*
X1285200Y-628767D01*
X1285800Y-628367D01*
X1286200Y-627834D01*
G01X1290700Y-628900D02*
Y-623567D01*
G01Y-624900D02*
X1291100Y-624233D01*
X1291700Y-623700D01*
X1292500Y-623567D01*
X1293200Y-623700D01*
X1293800Y-624233D01*
X1294100Y-625167D01*
Y-628900D01*
G01X1300400Y-623567D02*
Y-628900D01*
G01Y-621433D02*
X1300200Y-621300D01*
Y-621033D01*
X1300400Y-620900D01*
X1300600Y-621033D01*
Y-621300D01*
X1300400Y-621433D01*
G01X1310000Y-624233D02*
X1309300Y-623700D01*
X1308700Y-623567D01*
X1307900Y-623833D01*
X1307300Y-624367D01*
X1306900Y-625300D01*
X1306800Y-626233D01*
X1306900Y-627167D01*
X1307300Y-627967D01*
X1307900Y-628633D01*
X1308700Y-628900D01*
X1309400Y-628633D01*
X1310000Y-628100D01*
G01X1318200Y-628900D02*
Y-623567D01*
G01Y-624500D02*
X1317800Y-623967D01*
X1317200Y-623700D01*
X1316500Y-623567D01*
X1315800Y-623833D01*
X1315200Y-624367D01*
X1314800Y-625167D01*
X1314600Y-626233D01*
X1314800Y-627300D01*
X1315200Y-628100D01*
X1315800Y-628633D01*
X1316500Y-628900D01*
X1317200Y-628767D01*
X1317800Y-628367D01*
X1318200Y-627834D01*
G01X1324400Y-628900D02*
Y-620900D01*
G01X1342200D02*
Y-628900D01*
G01Y-627700D02*
X1341800Y-628367D01*
X1341200Y-628767D01*
X1340500Y-628900D01*
X1339700Y-628633D01*
X1339100Y-627967D01*
X1338700Y-627167D01*
X1338600Y-626233D01*
X1338700Y-625300D01*
X1339100Y-624500D01*
X1339700Y-623833D01*
X1340500Y-623567D01*
X1341200Y-623700D01*
X1341700Y-623967D01*
X1342200Y-624500D01*
G01X1347000Y-628900D02*
Y-623567D01*
G01Y-624633D02*
X1347500Y-624100D01*
X1348000Y-623700D01*
X1348700Y-623567D01*
X1349200Y-623700D01*
X1349800Y-624100D01*
G01X1358200Y-628900D02*
Y-623567D01*
G01Y-624500D02*
X1357800Y-623967D01*
X1357200Y-623700D01*
X1356500Y-623567D01*
X1355800Y-623833D01*
X1355200Y-624367D01*
X1354800Y-625167D01*
X1354600Y-626233D01*
X1354800Y-627300D01*
X1355200Y-628100D01*
X1355800Y-628633D01*
X1356500Y-628900D01*
X1357200Y-628767D01*
X1357800Y-628367D01*
X1358200Y-627834D01*
G01X1361900Y-623567D02*
X1363100Y-628900D01*
X1364400Y-623567D01*
X1365700Y-628900D01*
X1366900Y-623567D01*
G01X1372400D02*
Y-628900D01*
G01Y-621433D02*
X1372200Y-621300D01*
Y-621033D01*
X1372400Y-620900D01*
X1372600Y-621033D01*
Y-621300D01*
X1372400Y-621433D01*
G01X1378700Y-628900D02*
Y-623567D01*
G01Y-624900D02*
X1379100Y-624233D01*
X1379700Y-623700D01*
X1380500Y-623567D01*
X1381200Y-623700D01*
X1381800Y-624233D01*
X1382100Y-625167D01*
Y-628900D01*
G01X1387000Y-630900D02*
X1387700Y-631433D01*
X1388500Y-631567D01*
X1389200Y-631433D01*
X1389800Y-630767D01*
X1390200Y-629833D01*
Y-623567D01*
G01Y-624633D02*
X1389800Y-624100D01*
X1389200Y-623700D01*
X1388500Y-623567D01*
X1387700Y-623833D01*
X1387200Y-624367D01*
X1386800Y-625300D01*
X1386600Y-626233D01*
X1386700Y-627033D01*
X1387100Y-627967D01*
X1387700Y-628633D01*
X1388500Y-628900D01*
X1389100Y-628767D01*
X1389800Y-628233D01*
X1390200Y-627700D01*
G01X1395700Y-631300D02*
X1397100Y-629433D01*
Y-627567D01*
X1395700D01*
Y-629433D01*
X1397100D01*
G01Y-626233D02*
Y-624367D01*
X1395700D01*
Y-626233D01*
X1397100D01*
G01X530000Y-609100D02*
Y-614833D01*
X530400Y-616034D01*
X531200Y-616833D01*
X532200Y-617100D01*
X533200Y-616833D01*
X534000Y-616034D01*
X534400Y-614833D01*
Y-609100D01*
G01X538500Y-617100D02*
Y-611767D01*
G01Y-613100D02*
X538900Y-612433D01*
X539500Y-611900D01*
X540300Y-611767D01*
X541000Y-611900D01*
X541600Y-612433D01*
X541900Y-613367D01*
Y-617100D01*
G01X548200Y-611767D02*
Y-617100D01*
G01Y-609633D02*
X548000Y-609500D01*
Y-609233D01*
X548200Y-609100D01*
X548400Y-609233D01*
Y-609500D01*
X548200Y-609633D01*
G01X556200Y-609100D02*
Y-617100D01*
G01X554800Y-611767D02*
X557600D01*
G01X573800Y-612433D02*
X573100Y-611900D01*
X572500Y-611767D01*
X571700Y-612033D01*
X571100Y-612567D01*
X570700Y-613500D01*
X570600Y-614433D01*
X570700Y-615367D01*
X571100Y-616167D01*
X571700Y-616833D01*
X572500Y-617100D01*
X573200Y-616833D01*
X573800Y-616300D01*
G01X580200Y-617100D02*
X579600Y-616967D01*
X579000Y-616433D01*
X578600Y-615500D01*
X578400Y-614433D01*
X578600Y-613367D01*
X579000Y-612433D01*
X579600Y-611900D01*
X580200Y-611767D01*
X580800Y-611900D01*
X581400Y-612433D01*
X581800Y-613367D01*
X581900Y-614433D01*
X581800Y-615500D01*
X581400Y-616433D01*
X580800Y-616967D01*
X580200Y-617100D01*
G01X586500D02*
Y-611767D01*
G01Y-613100D02*
X586900Y-612433D01*
X587500Y-611900D01*
X588300Y-611767D01*
X589000Y-611900D01*
X589600Y-612433D01*
X589900Y-613367D01*
Y-617100D01*
G01X594400Y-611767D02*
X596200Y-617100D01*
X598000Y-611767D01*
G01X602700Y-613500D02*
X605900D01*
X605600Y-612567D01*
X605100Y-612033D01*
X604400Y-611767D01*
X603700Y-611900D01*
X603100Y-612300D01*
X602700Y-613233D01*
X602500Y-614034D01*
Y-614833D01*
X602700Y-615633D01*
X603200Y-616433D01*
X603800Y-616967D01*
X604500Y-617100D01*
X605200Y-616833D01*
X605900Y-616034D01*
G01X610800Y-617100D02*
Y-611767D01*
G01Y-612833D02*
X611300Y-612300D01*
X611800Y-611900D01*
X612500Y-611767D01*
X613000Y-611900D01*
X613600Y-612300D01*
G01X618700Y-616167D02*
X619200Y-616700D01*
X619900Y-617100D01*
X620500D01*
X621100Y-616833D01*
X621500Y-616433D01*
X621700Y-615900D01*
X621600Y-615100D01*
X621200Y-614700D01*
X619400Y-613900D01*
X619000Y-612967D01*
X619200Y-612300D01*
X619600Y-611900D01*
X620200Y-611767D01*
X620800Y-611900D01*
X621400Y-612300D01*
G01X628200Y-611767D02*
Y-617100D01*
G01Y-609633D02*
X628000Y-609500D01*
Y-609233D01*
X628200Y-609100D01*
X628400Y-609233D01*
Y-609500D01*
X628200Y-609633D01*
G01X636200Y-617100D02*
X635600Y-616967D01*
X635000Y-616433D01*
X634600Y-615500D01*
X634400Y-614433D01*
X634600Y-613367D01*
X635000Y-612433D01*
X635600Y-611900D01*
X636200Y-611767D01*
X636800Y-611900D01*
X637400Y-612433D01*
X637800Y-613367D01*
X637900Y-614433D01*
X637800Y-615500D01*
X637400Y-616433D01*
X636800Y-616967D01*
X636200Y-617100D01*
G01X642500D02*
Y-611767D01*
G01Y-613100D02*
X642900Y-612433D01*
X643500Y-611900D01*
X644300Y-611767D01*
X645000Y-611900D01*
X645600Y-612433D01*
X645900Y-613367D01*
Y-617100D01*
G01X660200Y-611767D02*
Y-617100D01*
G01Y-609633D02*
X660000Y-609500D01*
Y-609233D01*
X660200Y-609100D01*
X660400Y-609233D01*
Y-609500D01*
X660200Y-609633D01*
G01X666700Y-616167D02*
X667200Y-616700D01*
X667900Y-617100D01*
X668500D01*
X669100Y-616833D01*
X669500Y-616433D01*
X669700Y-615900D01*
X669600Y-615100D01*
X669200Y-614700D01*
X667400Y-613900D01*
X667000Y-612967D01*
X667200Y-612300D01*
X667600Y-611900D01*
X668200Y-611767D01*
X668800Y-611900D01*
X669400Y-612300D01*
G01X674700Y-616167D02*
X675200Y-616700D01*
X675900Y-617100D01*
X676500D01*
X677100Y-616833D01*
X677500Y-616433D01*
X677700Y-615900D01*
X677600Y-615100D01*
X677200Y-614700D01*
X675400Y-613900D01*
X675000Y-612967D01*
X675200Y-612300D01*
X675600Y-611900D01*
X676200Y-611767D01*
X676800Y-611900D01*
X677400Y-612300D01*
G01X682500Y-611767D02*
Y-615500D01*
X682900Y-616433D01*
X683500Y-616967D01*
X684200Y-617100D01*
X684900Y-616967D01*
X685500Y-616433D01*
X685900Y-615500D01*
G01Y-617100D02*
Y-611767D01*
G01X690700Y-613500D02*
X693900D01*
X693600Y-612567D01*
X693100Y-612033D01*
X692400Y-611767D01*
X691700Y-611900D01*
X691100Y-612300D01*
X690700Y-613233D01*
X690500Y-614034D01*
Y-614833D01*
X690700Y-615633D01*
X691200Y-616433D01*
X691800Y-616967D01*
X692500Y-617100D01*
X693200Y-616833D01*
X693900Y-616034D01*
G01X700200Y-617367D02*
X700000Y-617233D01*
Y-616967D01*
X700200Y-616833D01*
X700400Y-616967D01*
Y-617233D01*
X700200Y-617367D01*
G01Y-613767D02*
X700000Y-613633D01*
Y-613367D01*
X700200Y-613233D01*
X700400Y-613367D01*
Y-613633D01*
X700200Y-613767D01*
G01X536200Y-577700D02*
Y-569700D01*
X535000Y-571300D01*
G01Y-577700D02*
X537400D01*
G01X544200D02*
Y-569700D01*
X543000Y-571300D01*
G01Y-577700D02*
X545400D01*
G01X535700Y-565200D02*
Y-557200D01*
X534500Y-558800D01*
G01Y-565200D02*
X536900D01*
G01X543700Y-557200D02*
X542900Y-557467D01*
X542300Y-558133D01*
X541900Y-558933D01*
X541600Y-560000D01*
X541500Y-561200D01*
X541600Y-562400D01*
X541900Y-563467D01*
X542300Y-564267D01*
X542900Y-564933D01*
X543700Y-565200D01*
X544500Y-564933D01*
X545100Y-564267D01*
X545500Y-563467D01*
X545800Y-562400D01*
X545900Y-561200D01*
X545800Y-560000D01*
X545500Y-558933D01*
X545100Y-558133D01*
X544500Y-557467D01*
X543700Y-557200D01*
G01X538500Y-551267D02*
X539200Y-551933D01*
X540000Y-552200D01*
X540800Y-551933D01*
X541500Y-551134D01*
X542000Y-549933D01*
X542200Y-548733D01*
Y-547267D01*
X542000Y-546067D01*
X541500Y-545000D01*
X540900Y-544467D01*
X540200Y-544200D01*
X539400Y-544467D01*
X538800Y-545000D01*
X538400Y-545800D01*
X538200Y-546867D01*
X538400Y-547800D01*
X538900Y-548733D01*
X539500Y-549267D01*
X540200Y-549400D01*
X541000Y-549134D01*
X541600Y-548467D01*
X542200Y-547267D01*
G01X540000Y-527700D02*
X540200Y-525967D01*
X540500Y-524500D01*
X540900Y-523167D01*
X541400Y-521700D01*
X542200Y-519700D01*
X538200D01*
G01X540200Y-539700D02*
X540900Y-539567D01*
X541700Y-539167D01*
X542200Y-538500D01*
X542400Y-537567D01*
X542200Y-536634D01*
X541600Y-535833D01*
X540700Y-535433D01*
X539700D01*
X539100Y-535167D01*
X538600Y-534500D01*
X538400Y-533567D01*
X538700Y-532633D01*
X539400Y-531967D01*
X540200Y-531700D01*
X541000Y-531967D01*
X541700Y-532633D01*
X542000Y-533567D01*
X541800Y-534500D01*
X541300Y-535167D01*
X540700Y-535433D01*
X539700D01*
X538800Y-535833D01*
X538200Y-536634D01*
X538000Y-537567D01*
X538200Y-538500D01*
X538700Y-539167D01*
X539500Y-539567D01*
X540200Y-539700D01*
G01X573200Y-577200D02*
Y-569200D01*
X575700D01*
X576500Y-569600D01*
X577000Y-570133D01*
X577200Y-571200D01*
X577000Y-572267D01*
X576400Y-572933D01*
X575700Y-573333D01*
X573200D01*
G01X575700D02*
X577200Y-577200D01*
G01X583200D02*
X582600Y-577067D01*
X582000Y-576533D01*
X581600Y-575600D01*
X581400Y-574533D01*
X581600Y-573467D01*
X582000Y-572533D01*
X582600Y-572000D01*
X583200Y-571867D01*
X583800Y-572000D01*
X584400Y-572533D01*
X584800Y-573467D01*
X584900Y-574533D01*
X584800Y-575600D01*
X584400Y-576533D01*
X583800Y-577067D01*
X583200Y-577200D01*
G01X589500Y-571867D02*
Y-575600D01*
X589900Y-576533D01*
X590500Y-577067D01*
X591200Y-577200D01*
X591900Y-577067D01*
X592500Y-576533D01*
X592900Y-575600D01*
G01Y-577200D02*
Y-571867D01*
G01X597800Y-579200D02*
X598500Y-579733D01*
X599300Y-579867D01*
X600000Y-579733D01*
X600600Y-579067D01*
X601000Y-578133D01*
Y-571867D01*
G01Y-572933D02*
X600600Y-572400D01*
X600000Y-572000D01*
X599300Y-571867D01*
X598500Y-572133D01*
X598000Y-572667D01*
X597600Y-573600D01*
X597400Y-574533D01*
X597500Y-575333D01*
X597900Y-576267D01*
X598500Y-576933D01*
X599300Y-577200D01*
X599900Y-577067D01*
X600600Y-576533D01*
X601000Y-576000D01*
G01X605500Y-577200D02*
Y-569200D01*
G01Y-573067D02*
X606000Y-572400D01*
X606500Y-572000D01*
X607300Y-571867D01*
X607900Y-572000D01*
X608600Y-572533D01*
X608900Y-573333D01*
Y-577200D01*
G01X613500D02*
Y-571867D01*
G01Y-573200D02*
X613900Y-572533D01*
X614500Y-572000D01*
X615300Y-571867D01*
X616000Y-572000D01*
X616600Y-572533D01*
X616900Y-573467D01*
Y-577200D01*
G01X621700Y-573600D02*
X624900D01*
X624600Y-572667D01*
X624100Y-572133D01*
X623400Y-571867D01*
X622700Y-572000D01*
X622100Y-572400D01*
X621700Y-573333D01*
X621500Y-574134D01*
Y-574933D01*
X621700Y-575733D01*
X622200Y-576533D01*
X622800Y-577067D01*
X623500Y-577200D01*
X624200Y-576933D01*
X624900Y-576134D01*
G01X629700Y-576267D02*
X630200Y-576800D01*
X630900Y-577200D01*
X631500D01*
X632100Y-576933D01*
X632500Y-576533D01*
X632700Y-576000D01*
X632600Y-575200D01*
X632200Y-574800D01*
X630400Y-574000D01*
X630000Y-573067D01*
X630200Y-572400D01*
X630600Y-572000D01*
X631200Y-571867D01*
X631800Y-572000D01*
X632400Y-572400D01*
G01X637700Y-576267D02*
X638200Y-576800D01*
X638900Y-577200D01*
X639500D01*
X640100Y-576933D01*
X640500Y-576533D01*
X640700Y-576000D01*
X640600Y-575200D01*
X640200Y-574800D01*
X638400Y-574000D01*
X638000Y-573067D01*
X638200Y-572400D01*
X638600Y-572000D01*
X639200Y-571867D01*
X639800Y-572000D01*
X640400Y-572400D01*
G01X538800Y-511367D02*
X539500Y-510433D01*
X540100Y-509900D01*
X540900Y-509633D01*
X541600Y-509900D01*
X542100Y-510433D01*
X542500Y-511233D01*
X542600Y-512167D01*
X542500Y-512967D01*
X542100Y-513767D01*
X541500Y-514433D01*
X540800Y-514700D01*
X540000Y-514433D01*
X539300Y-513634D01*
X538900Y-512433D01*
X538800Y-511100D01*
X539000Y-509367D01*
X539300Y-508433D01*
X539800Y-507500D01*
X540500Y-506833D01*
X541200Y-506700D01*
X541900Y-506967D01*
X542400Y-507633D01*
G01X541900Y-476700D02*
Y-468700D01*
X538200Y-474433D01*
X543200D01*
G01X538500Y-494000D02*
X539100Y-494667D01*
X539800Y-495067D01*
X540700Y-495200D01*
X541600Y-494933D01*
X542300Y-494400D01*
X542800Y-493467D01*
X542900Y-492400D01*
X542700Y-491333D01*
X542200Y-490667D01*
X541500Y-490133D01*
X540800Y-490000D01*
X540100Y-490133D01*
X539200Y-490667D01*
X539500Y-487200D01*
X542200D01*
G01X569600Y-485200D02*
Y-477200D01*
G01X573800D02*
Y-485200D01*
G01Y-481200D02*
X569600D01*
G01X579700Y-485200D02*
X579100Y-485067D01*
X578500Y-484533D01*
X578100Y-483600D01*
X577900Y-482533D01*
X578100Y-481467D01*
X578500Y-480533D01*
X579100Y-480000D01*
X579700Y-479867D01*
X580300Y-480000D01*
X580900Y-480533D01*
X581300Y-481467D01*
X581400Y-482533D01*
X581300Y-483600D01*
X580900Y-484533D01*
X580300Y-485067D01*
X579700Y-485200D01*
G01X587700D02*
Y-477200D01*
G01X594200Y-481600D02*
X597400D01*
X597100Y-480667D01*
X596600Y-480133D01*
X595900Y-479867D01*
X595200Y-480000D01*
X594600Y-480400D01*
X594200Y-481333D01*
X594000Y-482134D01*
Y-482933D01*
X594200Y-483733D01*
X594700Y-484533D01*
X595300Y-485067D01*
X596000Y-485200D01*
X596700Y-484933D01*
X597400Y-484134D01*
G01X538500Y-451100D02*
X539100Y-452033D01*
X539900Y-452567D01*
X540800Y-452700D01*
X541600Y-452567D01*
X542400Y-451900D01*
X542900Y-451100D01*
X543000Y-450300D01*
X542800Y-449367D01*
X542100Y-448700D01*
X541400Y-448433D01*
X540500D01*
G01X541400D02*
X542000Y-448033D01*
X542500Y-447367D01*
X542700Y-446567D01*
X542500Y-445767D01*
X542000Y-445100D01*
X541100Y-444700D01*
X540200Y-444833D01*
X539300Y-445367D01*
G01Y-433033D02*
X539900Y-432233D01*
X540600Y-431833D01*
X541400Y-431700D01*
X542400Y-431967D01*
X543100Y-432633D01*
X543300Y-433433D01*
X543200Y-434234D01*
X542800Y-434900D01*
X540800Y-436233D01*
X539900Y-437167D01*
X539300Y-438500D01*
X539100Y-439700D01*
X543300D01*
G01X541200Y-427200D02*
Y-419200D01*
X540000Y-420800D01*
G01Y-427200D02*
X542400D01*
G01X531400Y-411700D02*
Y-403700D01*
X536000Y-411700D01*
Y-403700D01*
G01X541700Y-411700D02*
X540900Y-411567D01*
X540200Y-411033D01*
X539600Y-410233D01*
X539200Y-409300D01*
X539000Y-408233D01*
Y-407167D01*
X539200Y-406100D01*
X539600Y-405167D01*
X540200Y-404367D01*
X540900Y-403833D01*
X541700Y-403700D01*
X542500Y-403833D01*
X543200Y-404367D01*
X543800Y-405167D01*
X544200Y-406100D01*
X544400Y-407167D01*
Y-408233D01*
X544200Y-409300D01*
X543800Y-410233D01*
X543200Y-411033D01*
X542500Y-411567D01*
X541700Y-411700D01*
G01X549700Y-411967D02*
X549500Y-411833D01*
Y-411567D01*
X549700Y-411433D01*
X549900Y-411567D01*
Y-411833D01*
X549700Y-411967D01*
G01X557600Y-427700D02*
Y-419700D01*
G01X561800D02*
Y-427700D01*
G01Y-423700D02*
X557600D01*
G01X567700Y-427700D02*
X567100Y-427567D01*
X566500Y-427033D01*
X566100Y-426100D01*
X565900Y-425033D01*
X566100Y-423967D01*
X566500Y-423033D01*
X567100Y-422500D01*
X567700Y-422367D01*
X568300Y-422500D01*
X568900Y-423033D01*
X569300Y-423967D01*
X569400Y-425033D01*
X569300Y-426100D01*
X568900Y-427033D01*
X568300Y-427567D01*
X567700Y-427700D01*
G01X575700D02*
Y-419700D01*
G01X582200Y-424100D02*
X585400D01*
X585100Y-423167D01*
X584600Y-422633D01*
X583900Y-422367D01*
X583200Y-422500D01*
X582600Y-422900D01*
X582200Y-423833D01*
X582000Y-424634D01*
Y-425433D01*
X582200Y-426233D01*
X582700Y-427033D01*
X583300Y-427567D01*
X584000Y-427700D01*
X584700Y-427433D01*
X585400Y-426634D01*
G01X587900Y-667600D02*
Y-675600D01*
G01X585600Y-667600D02*
X590200D01*
G01X594200Y-675600D02*
Y-667600D01*
G01Y-671467D02*
X594700Y-670800D01*
X595200Y-670400D01*
X596000Y-670267D01*
X596600Y-670400D01*
X597300Y-670933D01*
X597600Y-671733D01*
Y-675600D01*
G01X602400Y-672000D02*
X605600D01*
X605300Y-671067D01*
X604800Y-670533D01*
X604100Y-670267D01*
X603400Y-670400D01*
X602800Y-670800D01*
X602400Y-671733D01*
X602200Y-672534D01*
Y-673333D01*
X602400Y-674133D01*
X602900Y-674933D01*
X603500Y-675467D01*
X604200Y-675600D01*
X604900Y-675333D01*
X605600Y-674534D01*
G01X610500Y-675600D02*
Y-670267D01*
G01Y-671333D02*
X611000Y-670800D01*
X611500Y-670400D01*
X612200Y-670267D01*
X612700Y-670400D01*
X613300Y-670800D01*
G01X618400Y-672000D02*
X621600D01*
X621300Y-671067D01*
X620800Y-670533D01*
X620100Y-670267D01*
X619400Y-670400D01*
X618800Y-670800D01*
X618400Y-671733D01*
X618200Y-672534D01*
Y-673333D01*
X618400Y-674133D01*
X618900Y-674933D01*
X619500Y-675467D01*
X620200Y-675600D01*
X620900Y-675333D01*
X621600Y-674534D01*
G01X627300Y-675600D02*
Y-668800D01*
X627500Y-668133D01*
X627900Y-667733D01*
X628500Y-667600D01*
X629100Y-667867D01*
X629400Y-668533D01*
G01X628200Y-670800D02*
X626200D01*
G01X635900Y-675600D02*
X635300Y-675467D01*
X634700Y-674933D01*
X634300Y-674000D01*
X634100Y-672933D01*
X634300Y-671867D01*
X634700Y-670933D01*
X635300Y-670400D01*
X635900Y-670267D01*
X636500Y-670400D01*
X637100Y-670933D01*
X637500Y-671867D01*
X637600Y-672933D01*
X637500Y-674000D01*
X637100Y-674933D01*
X636500Y-675467D01*
X635900Y-675600D01*
G01X642500D02*
Y-670267D01*
G01Y-671333D02*
X643000Y-670800D01*
X643500Y-670400D01*
X644200Y-670267D01*
X644700Y-670400D01*
X645300Y-670800D01*
G01X650400Y-672000D02*
X653600D01*
X653300Y-671067D01*
X652800Y-670533D01*
X652100Y-670267D01*
X651400Y-670400D01*
X650800Y-670800D01*
X650400Y-671733D01*
X650200Y-672534D01*
Y-673333D01*
X650400Y-674133D01*
X650900Y-674933D01*
X651500Y-675467D01*
X652200Y-675600D01*
X652900Y-675333D01*
X653600Y-674534D01*
G01X659700Y-677067D02*
X660100Y-675333D01*
G01X674100Y-678267D02*
Y-670267D01*
G01Y-671467D02*
X674600Y-670800D01*
X675100Y-670400D01*
X675900Y-670267D01*
X676600Y-670400D01*
X677300Y-671067D01*
X677600Y-672000D01*
X677700Y-672933D01*
X677600Y-673867D01*
X677300Y-674800D01*
X676700Y-675333D01*
X675900Y-675600D01*
X675200Y-675467D01*
X674500Y-675067D01*
X674100Y-674534D01*
G01X683900Y-675600D02*
Y-667600D01*
G01X690400Y-672000D02*
X693600D01*
X693300Y-671067D01*
X692800Y-670533D01*
X692100Y-670267D01*
X691400Y-670400D01*
X690800Y-670800D01*
X690400Y-671733D01*
X690200Y-672534D01*
Y-673333D01*
X690400Y-674133D01*
X690900Y-674933D01*
X691500Y-675467D01*
X692200Y-675600D01*
X692900Y-675333D01*
X693600Y-674534D01*
G01X701700Y-675600D02*
Y-670267D01*
G01Y-671200D02*
X701300Y-670667D01*
X700700Y-670400D01*
X700000Y-670267D01*
X699300Y-670533D01*
X698700Y-671067D01*
X698300Y-671867D01*
X698100Y-672933D01*
X698300Y-674000D01*
X698700Y-674800D01*
X699300Y-675333D01*
X700000Y-675600D01*
X700700Y-675467D01*
X701300Y-675067D01*
X701700Y-674534D01*
G01X706400Y-674667D02*
X706900Y-675200D01*
X707600Y-675600D01*
X708200D01*
X708800Y-675333D01*
X709200Y-674933D01*
X709400Y-674400D01*
X709300Y-673600D01*
X708900Y-673200D01*
X707100Y-672400D01*
X706700Y-671467D01*
X706900Y-670800D01*
X707300Y-670400D01*
X707900Y-670267D01*
X708500Y-670400D01*
X709100Y-670800D01*
G01X714400Y-672000D02*
X717600D01*
X717300Y-671067D01*
X716800Y-670533D01*
X716100Y-670267D01*
X715400Y-670400D01*
X714800Y-670800D01*
X714400Y-671733D01*
X714200Y-672534D01*
Y-673333D01*
X714400Y-674133D01*
X714900Y-674933D01*
X715500Y-675467D01*
X716200Y-675600D01*
X716900Y-675333D01*
X717600Y-674534D01*
G01X731300Y-675600D02*
Y-668800D01*
X731500Y-668133D01*
X731900Y-667733D01*
X732500Y-667600D01*
X733100Y-667867D01*
X733400Y-668533D01*
G01X732200Y-670800D02*
X730200D01*
G01X739900Y-675600D02*
X739300Y-675467D01*
X738700Y-674933D01*
X738300Y-674000D01*
X738100Y-672933D01*
X738300Y-671867D01*
X738700Y-670933D01*
X739300Y-670400D01*
X739900Y-670267D01*
X740500Y-670400D01*
X741100Y-670933D01*
X741500Y-671867D01*
X741600Y-672933D01*
X741500Y-674000D01*
X741100Y-674933D01*
X740500Y-675467D01*
X739900Y-675600D01*
G01X747900D02*
Y-667600D01*
G01X755900Y-675600D02*
Y-667600D01*
G01X763900Y-675600D02*
X763300Y-675467D01*
X762700Y-674933D01*
X762300Y-674000D01*
X762100Y-672933D01*
X762300Y-671867D01*
X762700Y-670933D01*
X763300Y-670400D01*
X763900Y-670267D01*
X764500Y-670400D01*
X765100Y-670933D01*
X765500Y-671867D01*
X765600Y-672933D01*
X765500Y-674000D01*
X765100Y-674933D01*
X764500Y-675467D01*
X763900Y-675600D01*
G01X769400Y-670267D02*
X770600Y-675600D01*
X771900Y-670267D01*
X773200Y-675600D01*
X774400Y-670267D01*
G01X785700Y-674000D02*
X786300Y-674933D01*
X787100Y-675467D01*
X788000Y-675600D01*
X788800Y-675467D01*
X789600Y-674800D01*
X790100Y-674000D01*
X790200Y-673200D01*
X790000Y-672267D01*
X789300Y-671600D01*
X788600Y-671333D01*
X787700D01*
G01X788600D02*
X789200Y-670933D01*
X789700Y-670267D01*
X789900Y-669467D01*
X789700Y-668667D01*
X789200Y-668000D01*
X788300Y-667600D01*
X787400Y-667733D01*
X786500Y-668267D01*
G01X795900Y-675867D02*
X795700Y-675733D01*
Y-675467D01*
X795900Y-675333D01*
X796100Y-675467D01*
Y-675733D01*
X795900Y-675867D01*
G01X803900Y-675600D02*
Y-667600D01*
X802700Y-669200D01*
G01Y-675600D02*
X805100D01*
G01X811900D02*
X812600Y-675467D01*
X813400Y-675067D01*
X813900Y-674400D01*
X814100Y-673467D01*
X813900Y-672534D01*
X813300Y-671733D01*
X812400Y-671333D01*
X811400D01*
X810800Y-671067D01*
X810300Y-670400D01*
X810100Y-669467D01*
X810400Y-668533D01*
X811100Y-667867D01*
X811900Y-667600D01*
X812700Y-667867D01*
X813400Y-668533D01*
X813700Y-669467D01*
X813500Y-670400D01*
X813000Y-671067D01*
X812400Y-671333D01*
X811400D01*
X810500Y-671733D01*
X809900Y-672534D01*
X809700Y-673467D01*
X809900Y-674400D01*
X810400Y-675067D01*
X811200Y-675467D01*
X811900Y-675600D01*
G01X816900D02*
Y-670267D01*
G01Y-671733D02*
X817200Y-671067D01*
X817700Y-670533D01*
X818400Y-670267D01*
X819100Y-670533D01*
X819600Y-671067D01*
X819900Y-671733D01*
Y-675600D01*
G01Y-671733D02*
X820200Y-671067D01*
X820700Y-670533D01*
X821400Y-670267D01*
X822100Y-670533D01*
X822600Y-671067D01*
X822900Y-671867D01*
Y-675600D01*
G01X824900D02*
Y-670267D01*
G01Y-671733D02*
X825200Y-671067D01*
X825700Y-670533D01*
X826400Y-670267D01*
X827100Y-670533D01*
X827600Y-671067D01*
X827900Y-671733D01*
Y-675600D01*
G01Y-671733D02*
X828200Y-671067D01*
X828700Y-670533D01*
X829400Y-670267D01*
X830100Y-670533D01*
X830600Y-671067D01*
X830900Y-671867D01*
Y-675600D01*
G01X843900Y-667600D02*
Y-675600D01*
G01X842500Y-670267D02*
X845300D01*
G01X851900Y-675600D02*
X851300Y-675467D01*
X850700Y-674933D01*
X850300Y-674000D01*
X850100Y-672933D01*
X850300Y-671867D01*
X850700Y-670933D01*
X851300Y-670400D01*
X851900Y-670267D01*
X852500Y-670400D01*
X853100Y-670933D01*
X853500Y-671867D01*
X853600Y-672933D01*
X853500Y-674000D01*
X853100Y-674933D01*
X852500Y-675467D01*
X851900Y-675600D01*
G01X866100Y-678267D02*
Y-670267D01*
G01Y-671467D02*
X866600Y-670800D01*
X867100Y-670400D01*
X867900Y-670267D01*
X868600Y-670400D01*
X869300Y-671067D01*
X869600Y-672000D01*
X869700Y-672933D01*
X869600Y-673867D01*
X869300Y-674800D01*
X868700Y-675333D01*
X867900Y-675600D01*
X867200Y-675467D01*
X866500Y-675067D01*
X866100Y-674534D01*
G01X874500Y-675600D02*
Y-670267D01*
G01Y-671333D02*
X875000Y-670800D01*
X875500Y-670400D01*
X876200Y-670267D01*
X876700Y-670400D01*
X877300Y-670800D01*
G01X883900Y-675600D02*
X883300Y-675467D01*
X882700Y-674933D01*
X882300Y-674000D01*
X882100Y-672933D01*
X882300Y-671867D01*
X882700Y-670933D01*
X883300Y-670400D01*
X883900Y-670267D01*
X884500Y-670400D01*
X885100Y-670933D01*
X885500Y-671867D01*
X885600Y-672933D01*
X885500Y-674000D01*
X885100Y-674933D01*
X884500Y-675467D01*
X883900Y-675600D01*
G01X893700Y-667600D02*
Y-675600D01*
G01Y-674400D02*
X893300Y-675067D01*
X892700Y-675467D01*
X892000Y-675600D01*
X891200Y-675333D01*
X890600Y-674667D01*
X890200Y-673867D01*
X890100Y-672933D01*
X890200Y-672000D01*
X890600Y-671200D01*
X891200Y-670533D01*
X892000Y-670267D01*
X892700Y-670400D01*
X893200Y-670667D01*
X893700Y-671200D01*
G01X898200Y-670267D02*
Y-674000D01*
X898600Y-674933D01*
X899200Y-675467D01*
X899900Y-675600D01*
X900600Y-675467D01*
X901200Y-674933D01*
X901600Y-674000D01*
G01Y-675600D02*
Y-670267D01*
G01X909500Y-670933D02*
X908800Y-670400D01*
X908200Y-670267D01*
X907400Y-670533D01*
X906800Y-671067D01*
X906400Y-672000D01*
X906300Y-672933D01*
X906400Y-673867D01*
X906800Y-674667D01*
X907400Y-675333D01*
X908200Y-675600D01*
X908900Y-675333D01*
X909500Y-674800D01*
G01X914400Y-672000D02*
X917600D01*
X917300Y-671067D01*
X916800Y-670533D01*
X916100Y-670267D01*
X915400Y-670400D01*
X914800Y-670800D01*
X914400Y-671733D01*
X914200Y-672534D01*
Y-673333D01*
X914400Y-674133D01*
X914900Y-674933D01*
X915500Y-675467D01*
X916200Y-675600D01*
X916900Y-675333D01*
X917600Y-674534D01*
G01X931900Y-667600D02*
Y-675600D01*
G01X930500Y-670267D02*
X933300D01*
G01X938200Y-675600D02*
Y-667600D01*
G01Y-671467D02*
X938700Y-670800D01*
X939200Y-670400D01*
X940000Y-670267D01*
X940600Y-670400D01*
X941300Y-670933D01*
X941600Y-671733D01*
Y-675600D01*
G01X947900Y-670267D02*
Y-675600D01*
G01Y-668133D02*
X947700Y-668000D01*
Y-667733D01*
X947900Y-667600D01*
X948100Y-667733D01*
Y-668000D01*
X947900Y-668133D01*
G01X954400Y-674667D02*
X954900Y-675200D01*
X955600Y-675600D01*
X956200D01*
X956800Y-675333D01*
X957200Y-674933D01*
X957400Y-674400D01*
X957300Y-673600D01*
X956900Y-673200D01*
X955100Y-672400D01*
X954700Y-671467D01*
X954900Y-670800D01*
X955300Y-670400D01*
X955900Y-670267D01*
X956500Y-670400D01*
X957100Y-670800D01*
G01X970100Y-675600D02*
Y-667600D01*
G01Y-671600D02*
X970600Y-670800D01*
X971200Y-670400D01*
X971800Y-670267D01*
X972700Y-670533D01*
X973300Y-671067D01*
X973700Y-672000D01*
Y-673067D01*
X973500Y-674133D01*
X973100Y-674933D01*
X972400Y-675467D01*
X971800Y-675600D01*
X971200Y-675467D01*
X970600Y-675067D01*
X970100Y-674400D01*
G01X979900Y-675600D02*
X979300Y-675467D01*
X978700Y-674933D01*
X978300Y-674000D01*
X978100Y-672933D01*
X978300Y-671867D01*
X978700Y-670933D01*
X979300Y-670400D01*
X979900Y-670267D01*
X980500Y-670400D01*
X981100Y-670933D01*
X981500Y-671867D01*
X981600Y-672933D01*
X981500Y-674000D01*
X981100Y-674933D01*
X980500Y-675467D01*
X979900Y-675600D01*
G01X989700D02*
Y-670267D01*
G01Y-671200D02*
X989300Y-670667D01*
X988700Y-670400D01*
X988000Y-670267D01*
X987300Y-670533D01*
X986700Y-671067D01*
X986300Y-671867D01*
X986100Y-672933D01*
X986300Y-674000D01*
X986700Y-674800D01*
X987300Y-675333D01*
X988000Y-675600D01*
X988700Y-675467D01*
X989300Y-675067D01*
X989700Y-674534D01*
G01X994500Y-675600D02*
Y-670267D01*
G01Y-671333D02*
X995000Y-670800D01*
X995500Y-670400D01*
X996200Y-670267D01*
X996700Y-670400D01*
X997300Y-670800D01*
G01X1005700Y-667600D02*
Y-675600D01*
G01Y-674400D02*
X1005300Y-675067D01*
X1004700Y-675467D01*
X1004000Y-675600D01*
X1003200Y-675333D01*
X1002600Y-674667D01*
X1002200Y-673867D01*
X1002100Y-672933D01*
X1002200Y-672000D01*
X1002600Y-671200D01*
X1003200Y-670533D01*
X1004000Y-670267D01*
X1004700Y-670400D01*
X1005200Y-670667D01*
X1005700Y-671200D01*
G01X1011900Y-675867D02*
X1011700Y-675733D01*
Y-675467D01*
X1011900Y-675333D01*
X1012100Y-675467D01*
Y-675733D01*
X1011900Y-675867D01*
G01X587700Y-657600D02*
Y-665600D01*
G01X585400Y-657600D02*
X590000D01*
G01X594000Y-665600D02*
Y-657600D01*
G01Y-661467D02*
X594500Y-660800D01*
X595000Y-660400D01*
X595800Y-660267D01*
X596400Y-660400D01*
X597100Y-660933D01*
X597400Y-661733D01*
Y-665600D01*
G01X602200Y-662000D02*
X605400D01*
X605100Y-661067D01*
X604600Y-660533D01*
X603900Y-660267D01*
X603200Y-660400D01*
X602600Y-660800D01*
X602200Y-661733D01*
X602000Y-662534D01*
Y-663333D01*
X602200Y-664133D01*
X602700Y-664933D01*
X603300Y-665467D01*
X604000Y-665600D01*
X604700Y-665333D01*
X605400Y-664534D01*
G01X610000Y-665600D02*
Y-660267D01*
G01Y-661600D02*
X610400Y-660933D01*
X611000Y-660400D01*
X611800Y-660267D01*
X612500Y-660400D01*
X613100Y-660933D01*
X613400Y-661867D01*
Y-665600D01*
G01X629300Y-660933D02*
X628600Y-660400D01*
X628000Y-660267D01*
X627200Y-660533D01*
X626600Y-661067D01*
X626200Y-662000D01*
X626100Y-662933D01*
X626200Y-663867D01*
X626600Y-664667D01*
X627200Y-665333D01*
X628000Y-665600D01*
X628700Y-665333D01*
X629300Y-664800D01*
G01X635700Y-665600D02*
X635100Y-665467D01*
X634500Y-664933D01*
X634100Y-664000D01*
X633900Y-662933D01*
X634100Y-661867D01*
X634500Y-660933D01*
X635100Y-660400D01*
X635700Y-660267D01*
X636300Y-660400D01*
X636900Y-660933D01*
X637300Y-661867D01*
X637400Y-662933D01*
X637300Y-664000D01*
X636900Y-664933D01*
X636300Y-665467D01*
X635700Y-665600D01*
G01X642000D02*
Y-660267D01*
G01Y-661600D02*
X642400Y-660933D01*
X643000Y-660400D01*
X643800Y-660267D01*
X644500Y-660400D01*
X645100Y-660933D01*
X645400Y-661867D01*
Y-665600D01*
G01X649900Y-660267D02*
X651700Y-665600D01*
X653500Y-660267D01*
G01X658200Y-662000D02*
X661400D01*
X661100Y-661067D01*
X660600Y-660533D01*
X659900Y-660267D01*
X659200Y-660400D01*
X658600Y-660800D01*
X658200Y-661733D01*
X658000Y-662534D01*
Y-663333D01*
X658200Y-664133D01*
X658700Y-664933D01*
X659300Y-665467D01*
X660000Y-665600D01*
X660700Y-665333D01*
X661400Y-664534D01*
G01X666300Y-665600D02*
Y-660267D01*
G01Y-661333D02*
X666800Y-660800D01*
X667300Y-660400D01*
X668000Y-660267D01*
X668500Y-660400D01*
X669100Y-660800D01*
G01X675700Y-657600D02*
Y-665600D01*
G01X674300Y-660267D02*
X677100D01*
G01X689500Y-664000D02*
X690100Y-664933D01*
X690900Y-665467D01*
X691800Y-665600D01*
X692600Y-665467D01*
X693400Y-664800D01*
X693900Y-664000D01*
X694000Y-663200D01*
X693800Y-662267D01*
X693100Y-661600D01*
X692400Y-661333D01*
X691500D01*
G01X692400D02*
X693000Y-660933D01*
X693500Y-660267D01*
X693700Y-659467D01*
X693500Y-658667D01*
X693000Y-658000D01*
X692100Y-657600D01*
X691200Y-657733D01*
X690300Y-658267D01*
G01X699700Y-665867D02*
X699500Y-665733D01*
Y-665467D01*
X699700Y-665333D01*
X699900Y-665467D01*
Y-665733D01*
X699700Y-665867D01*
G01X707700Y-665600D02*
Y-657600D01*
X706500Y-659200D01*
G01Y-665600D02*
X708900D01*
G01X715700D02*
X716400Y-665467D01*
X717200Y-665067D01*
X717700Y-664400D01*
X717900Y-663467D01*
X717700Y-662534D01*
X717100Y-661733D01*
X716200Y-661333D01*
X715200D01*
X714600Y-661067D01*
X714100Y-660400D01*
X713900Y-659467D01*
X714200Y-658533D01*
X714900Y-657867D01*
X715700Y-657600D01*
X716500Y-657867D01*
X717200Y-658533D01*
X717500Y-659467D01*
X717300Y-660400D01*
X716800Y-661067D01*
X716200Y-661333D01*
X715200D01*
X714300Y-661733D01*
X713700Y-662534D01*
X713500Y-663467D01*
X713700Y-664400D01*
X714200Y-665067D01*
X715000Y-665467D01*
X715700Y-665600D01*
G01X720700D02*
Y-660267D01*
G01Y-661733D02*
X721000Y-661067D01*
X721500Y-660533D01*
X722200Y-660267D01*
X722900Y-660533D01*
X723400Y-661067D01*
X723700Y-661733D01*
Y-665600D01*
G01Y-661733D02*
X724000Y-661067D01*
X724500Y-660533D01*
X725200Y-660267D01*
X725900Y-660533D01*
X726400Y-661067D01*
X726700Y-661867D01*
Y-665600D01*
G01X728700D02*
Y-660267D01*
G01Y-661733D02*
X729000Y-661067D01*
X729500Y-660533D01*
X730200Y-660267D01*
X730900Y-660533D01*
X731400Y-661067D01*
X731700Y-661733D01*
Y-665600D01*
G01Y-661733D02*
X732000Y-661067D01*
X732500Y-660533D01*
X733200Y-660267D01*
X733900Y-660533D01*
X734400Y-661067D01*
X734700Y-661867D01*
Y-665600D01*
G01X747700Y-660267D02*
Y-665600D01*
G01Y-658133D02*
X747500Y-658000D01*
Y-657733D01*
X747700Y-657600D01*
X747900Y-657733D01*
Y-658000D01*
X747700Y-658133D01*
G01X754000Y-665600D02*
Y-660267D01*
G01Y-661600D02*
X754400Y-660933D01*
X755000Y-660400D01*
X755800Y-660267D01*
X756500Y-660400D01*
X757100Y-660933D01*
X757400Y-661867D01*
Y-665600D01*
G01X763700Y-657600D02*
Y-665600D01*
G01X762300Y-660267D02*
X765100D01*
G01X771700Y-665600D02*
X771100Y-665467D01*
X770500Y-664933D01*
X770100Y-664000D01*
X769900Y-662933D01*
X770100Y-661867D01*
X770500Y-660933D01*
X771100Y-660400D01*
X771700Y-660267D01*
X772300Y-660400D01*
X772900Y-660933D01*
X773300Y-661867D01*
X773400Y-662933D01*
X773300Y-664000D01*
X772900Y-664933D01*
X772300Y-665467D01*
X771700Y-665600D01*
G01X787700D02*
Y-657600D01*
X786500Y-659200D01*
G01Y-665600D02*
X788900D01*
G01X793800Y-658933D02*
X794400Y-658133D01*
X795100Y-657733D01*
X795900Y-657600D01*
X796900Y-657867D01*
X797600Y-658533D01*
X797800Y-659333D01*
X797700Y-660134D01*
X797300Y-660800D01*
X795300Y-662133D01*
X794400Y-663067D01*
X793800Y-664400D01*
X793600Y-665600D01*
X797800D01*
G01X801500Y-664400D02*
X802100Y-665067D01*
X802800Y-665467D01*
X803700Y-665600D01*
X804600Y-665333D01*
X805300Y-664800D01*
X805800Y-663867D01*
X805900Y-662800D01*
X805700Y-661733D01*
X805200Y-661067D01*
X804500Y-660533D01*
X803800Y-660400D01*
X803100Y-660533D01*
X802200Y-661067D01*
X802500Y-657600D01*
X805200D01*
G01X811700Y-665867D02*
X811500Y-665733D01*
Y-665467D01*
X811700Y-665333D01*
X811900Y-665467D01*
Y-665733D01*
X811700Y-665867D01*
G01X819700Y-665600D02*
Y-657600D01*
X818500Y-659200D01*
G01Y-665600D02*
X820900D01*
G01X826000Y-664667D02*
X826700Y-665333D01*
X827500Y-665600D01*
X828300Y-665333D01*
X829000Y-664534D01*
X829500Y-663333D01*
X829700Y-662133D01*
Y-660667D01*
X829500Y-659467D01*
X829000Y-658400D01*
X828400Y-657867D01*
X827700Y-657600D01*
X826900Y-657867D01*
X826300Y-658400D01*
X825900Y-659200D01*
X825700Y-660267D01*
X825900Y-661200D01*
X826400Y-662133D01*
X827000Y-662667D01*
X827700Y-662800D01*
X828500Y-662534D01*
X829100Y-661867D01*
X829700Y-660667D01*
G01X833800Y-662267D02*
X834500Y-661333D01*
X835100Y-660800D01*
X835900Y-660533D01*
X836600Y-660800D01*
X837100Y-661333D01*
X837500Y-662133D01*
X837600Y-663067D01*
X837500Y-663867D01*
X837100Y-664667D01*
X836500Y-665333D01*
X835800Y-665600D01*
X835000Y-665333D01*
X834300Y-664534D01*
X833900Y-663333D01*
X833800Y-662000D01*
X834000Y-660267D01*
X834300Y-659333D01*
X834800Y-658400D01*
X835500Y-657733D01*
X836200Y-657600D01*
X836900Y-657867D01*
X837400Y-658533D01*
G01X843700Y-665600D02*
X844400Y-665467D01*
X845200Y-665067D01*
X845700Y-664400D01*
X845900Y-663467D01*
X845700Y-662534D01*
X845100Y-661733D01*
X844200Y-661333D01*
X843200D01*
X842600Y-661067D01*
X842100Y-660400D01*
X841900Y-659467D01*
X842200Y-658533D01*
X842900Y-657867D01*
X843700Y-657600D01*
X844500Y-657867D01*
X845200Y-658533D01*
X845500Y-659467D01*
X845300Y-660400D01*
X844800Y-661067D01*
X844200Y-661333D01*
X843200D01*
X842300Y-661733D01*
X841700Y-662534D01*
X841500Y-663467D01*
X841700Y-664400D01*
X842200Y-665067D01*
X843000Y-665467D01*
X843700Y-665600D01*
G01X848700D02*
Y-660267D01*
G01Y-661733D02*
X849000Y-661067D01*
X849500Y-660533D01*
X850200Y-660267D01*
X850900Y-660533D01*
X851400Y-661067D01*
X851700Y-661733D01*
Y-665600D01*
G01Y-661733D02*
X852000Y-661067D01*
X852500Y-660533D01*
X853200Y-660267D01*
X853900Y-660533D01*
X854400Y-661067D01*
X854700Y-661867D01*
Y-665600D01*
G01X859700Y-660267D02*
Y-665600D01*
G01Y-658133D02*
X859500Y-658000D01*
Y-657733D01*
X859700Y-657600D01*
X859900Y-657733D01*
Y-658000D01*
X859700Y-658133D01*
G01X867700Y-665600D02*
Y-657600D01*
G01X875500Y-667067D02*
X875900Y-665333D01*
G01X891700Y-657600D02*
Y-665600D01*
G01X890300Y-660267D02*
X893100D01*
G01X898000Y-665600D02*
Y-657600D01*
G01Y-661467D02*
X898500Y-660800D01*
X899000Y-660400D01*
X899800Y-660267D01*
X900400Y-660400D01*
X901100Y-660933D01*
X901400Y-661733D01*
Y-665600D01*
G01X906200Y-662000D02*
X909400D01*
X909100Y-661067D01*
X908600Y-660533D01*
X907900Y-660267D01*
X907200Y-660400D01*
X906600Y-660800D01*
X906200Y-661733D01*
X906000Y-662534D01*
Y-663333D01*
X906200Y-664133D01*
X906700Y-664933D01*
X907300Y-665467D01*
X908000Y-665600D01*
X908700Y-665333D01*
X909400Y-664534D01*
G01X925500Y-657600D02*
Y-665600D01*
G01Y-664400D02*
X925100Y-665067D01*
X924500Y-665467D01*
X923800Y-665600D01*
X923000Y-665333D01*
X922400Y-664667D01*
X922000Y-663867D01*
X921900Y-662933D01*
X922000Y-662000D01*
X922400Y-661200D01*
X923000Y-660533D01*
X923800Y-660267D01*
X924500Y-660400D01*
X925000Y-660667D01*
X925500Y-661200D01*
G01X931700Y-660267D02*
Y-665600D01*
G01Y-658133D02*
X931500Y-658000D01*
Y-657733D01*
X931700Y-657600D01*
X931900Y-657733D01*
Y-658000D01*
X931700Y-658133D01*
G01X939100Y-665600D02*
Y-658800D01*
X939300Y-658133D01*
X939700Y-657733D01*
X940300Y-657600D01*
X940900Y-657867D01*
X941200Y-658533D01*
G01X940000Y-660800D02*
X938000D01*
G01X947100Y-665600D02*
Y-658800D01*
X947300Y-658133D01*
X947700Y-657733D01*
X948300Y-657600D01*
X948900Y-657867D01*
X949200Y-658533D01*
G01X948000Y-660800D02*
X946000D01*
G01X954200Y-662000D02*
X957400D01*
X957100Y-661067D01*
X956600Y-660533D01*
X955900Y-660267D01*
X955200Y-660400D01*
X954600Y-660800D01*
X954200Y-661733D01*
X954000Y-662534D01*
Y-663333D01*
X954200Y-664133D01*
X954700Y-664933D01*
X955300Y-665467D01*
X956000Y-665600D01*
X956700Y-665333D01*
X957400Y-664534D01*
G01X962300Y-665600D02*
Y-660267D01*
G01Y-661333D02*
X962800Y-660800D01*
X963300Y-660400D01*
X964000Y-660267D01*
X964500Y-660400D01*
X965100Y-660800D01*
G01X970200Y-662000D02*
X973400D01*
X973100Y-661067D01*
X972600Y-660533D01*
X971900Y-660267D01*
X971200Y-660400D01*
X970600Y-660800D01*
X970200Y-661733D01*
X970000Y-662534D01*
Y-663333D01*
X970200Y-664133D01*
X970700Y-664933D01*
X971300Y-665467D01*
X972000Y-665600D01*
X972700Y-665333D01*
X973400Y-664534D01*
G01X978000Y-665600D02*
Y-660267D01*
G01Y-661600D02*
X978400Y-660933D01*
X979000Y-660400D01*
X979800Y-660267D01*
X980500Y-660400D01*
X981100Y-660933D01*
X981400Y-661867D01*
Y-665600D01*
G01X989300Y-660933D02*
X988600Y-660400D01*
X988000Y-660267D01*
X987200Y-660533D01*
X986600Y-661067D01*
X986200Y-662000D01*
X986100Y-662933D01*
X986200Y-663867D01*
X986600Y-664667D01*
X987200Y-665333D01*
X988000Y-665600D01*
X988700Y-665333D01*
X989300Y-664800D01*
G01X994200Y-662000D02*
X997400D01*
X997100Y-661067D01*
X996600Y-660533D01*
X995900Y-660267D01*
X995200Y-660400D01*
X994600Y-660800D01*
X994200Y-661733D01*
X994000Y-662534D01*
Y-663333D01*
X994200Y-664133D01*
X994700Y-664933D01*
X995300Y-665467D01*
X996000Y-665600D01*
X996700Y-665333D01*
X997400Y-664534D01*
G01X1009900Y-665600D02*
Y-657600D01*
G01Y-661600D02*
X1010400Y-660800D01*
X1011000Y-660400D01*
X1011600Y-660267D01*
X1012500Y-660533D01*
X1013100Y-661067D01*
X1013500Y-662000D01*
Y-663067D01*
X1013300Y-664133D01*
X1012900Y-664933D01*
X1012200Y-665467D01*
X1011600Y-665600D01*
X1011000Y-665467D01*
X1010400Y-665067D01*
X1009900Y-664400D01*
G01X1018200Y-662000D02*
X1021400D01*
X1021100Y-661067D01*
X1020600Y-660533D01*
X1019900Y-660267D01*
X1019200Y-660400D01*
X1018600Y-660800D01*
X1018200Y-661733D01*
X1018000Y-662534D01*
Y-663333D01*
X1018200Y-664133D01*
X1018700Y-664933D01*
X1019300Y-665467D01*
X1020000Y-665600D01*
X1020700Y-665333D01*
X1021400Y-664534D01*
G01X1027700Y-657600D02*
Y-665600D01*
G01X1026300Y-660267D02*
X1029100D01*
G01X1033200D02*
X1034400Y-665600D01*
X1035700Y-660267D01*
X1037000Y-665600D01*
X1038200Y-660267D01*
G01X1042200Y-662000D02*
X1045400D01*
X1045100Y-661067D01*
X1044600Y-660533D01*
X1043900Y-660267D01*
X1043200Y-660400D01*
X1042600Y-660800D01*
X1042200Y-661733D01*
X1042000Y-662534D01*
Y-663333D01*
X1042200Y-664133D01*
X1042700Y-664933D01*
X1043300Y-665467D01*
X1044000Y-665600D01*
X1044700Y-665333D01*
X1045400Y-664534D01*
G01X1050200Y-662000D02*
X1053400D01*
X1053100Y-661067D01*
X1052600Y-660533D01*
X1051900Y-660267D01*
X1051200Y-660400D01*
X1050600Y-660800D01*
X1050200Y-661733D01*
X1050000Y-662534D01*
Y-663333D01*
X1050200Y-664133D01*
X1050700Y-664933D01*
X1051300Y-665467D01*
X1052000Y-665600D01*
X1052700Y-665333D01*
X1053400Y-664534D01*
G01X1058000Y-665600D02*
Y-660267D01*
G01Y-661600D02*
X1058400Y-660933D01*
X1059000Y-660400D01*
X1059800Y-660267D01*
X1060500Y-660400D01*
X1061100Y-660933D01*
X1061400Y-661867D01*
Y-665600D01*
G01X1075700D02*
Y-657600D01*
X1074500Y-659200D01*
G01Y-665600D02*
X1076900D01*
G01X1081800Y-658933D02*
X1082400Y-658133D01*
X1083100Y-657733D01*
X1083900Y-657600D01*
X1084900Y-657867D01*
X1085600Y-658533D01*
X1085800Y-659333D01*
X1085700Y-660134D01*
X1085300Y-660800D01*
X1083300Y-662133D01*
X1082400Y-663067D01*
X1081800Y-664400D01*
X1081600Y-665600D01*
X1085800D01*
G01X1089800Y-662267D02*
X1090500Y-661333D01*
X1091100Y-660800D01*
X1091900Y-660533D01*
X1092600Y-660800D01*
X1093100Y-661333D01*
X1093500Y-662133D01*
X1093600Y-663067D01*
X1093500Y-663867D01*
X1093100Y-664667D01*
X1092500Y-665333D01*
X1091800Y-665600D01*
X1091000Y-665333D01*
X1090300Y-664534D01*
X1089900Y-663333D01*
X1089800Y-662000D01*
X1090000Y-660267D01*
X1090300Y-659333D01*
X1090800Y-658400D01*
X1091500Y-657733D01*
X1092200Y-657600D01*
X1092900Y-657867D01*
X1093400Y-658533D01*
G01X1096700Y-665600D02*
Y-660267D01*
G01Y-661733D02*
X1097000Y-661067D01*
X1097500Y-660533D01*
X1098200Y-660267D01*
X1098900Y-660533D01*
X1099400Y-661067D01*
X1099700Y-661733D01*
Y-665600D01*
G01Y-661733D02*
X1100000Y-661067D01*
X1100500Y-660533D01*
X1101200Y-660267D01*
X1101900Y-660533D01*
X1102400Y-661067D01*
X1102700Y-661867D01*
Y-665600D01*
G01X1107700Y-660267D02*
Y-665600D01*
G01Y-658133D02*
X1107500Y-658000D01*
Y-657733D01*
X1107700Y-657600D01*
X1107900Y-657733D01*
Y-658000D01*
X1107700Y-658133D01*
G01X1115700Y-665600D02*
Y-657600D01*
G01X1133500Y-665600D02*
Y-660267D01*
G01Y-661200D02*
X1133100Y-660667D01*
X1132500Y-660400D01*
X1131800Y-660267D01*
X1131100Y-660533D01*
X1130500Y-661067D01*
X1130100Y-661867D01*
X1129900Y-662933D01*
X1130100Y-664000D01*
X1130500Y-664800D01*
X1131100Y-665333D01*
X1131800Y-665600D01*
X1132500Y-665467D01*
X1133100Y-665067D01*
X1133500Y-664534D01*
G01X1138000Y-665600D02*
Y-660267D01*
G01Y-661600D02*
X1138400Y-660933D01*
X1139000Y-660400D01*
X1139800Y-660267D01*
X1140500Y-660400D01*
X1141100Y-660933D01*
X1141400Y-661867D01*
Y-665600D01*
G01X1149500Y-657600D02*
Y-665600D01*
G01Y-664400D02*
X1149100Y-665067D01*
X1148500Y-665467D01*
X1147800Y-665600D01*
X1147000Y-665333D01*
X1146400Y-664667D01*
X1146000Y-663867D01*
X1145900Y-662933D01*
X1146000Y-662000D01*
X1146400Y-661200D01*
X1147000Y-660533D01*
X1147800Y-660267D01*
X1148500Y-660400D01*
X1149000Y-660667D01*
X1149500Y-661200D01*
G01X1163700Y-665600D02*
Y-657600D01*
X1162500Y-659200D01*
G01Y-665600D02*
X1164900D01*
G01X1169800Y-658933D02*
X1170400Y-658133D01*
X1171100Y-657733D01*
X1171900Y-657600D01*
X1172900Y-657867D01*
X1173600Y-658533D01*
X1173800Y-659333D01*
X1173700Y-660134D01*
X1173300Y-660800D01*
X1171300Y-662133D01*
X1170400Y-663067D01*
X1169800Y-664400D01*
X1169600Y-665600D01*
X1173800D01*
G01X1177500Y-664400D02*
X1178100Y-665067D01*
X1178800Y-665467D01*
X1179700Y-665600D01*
X1180600Y-665333D01*
X1181300Y-664800D01*
X1181800Y-663867D01*
X1181900Y-662800D01*
X1181700Y-661733D01*
X1181200Y-661067D01*
X1180500Y-660533D01*
X1179800Y-660400D01*
X1179100Y-660533D01*
X1178200Y-661067D01*
X1178500Y-657600D01*
X1181200D01*
G01X1187700Y-665867D02*
X1187500Y-665733D01*
Y-665467D01*
X1187700Y-665333D01*
X1187900Y-665467D01*
Y-665733D01*
X1187700Y-665867D01*
G01X1195700Y-665600D02*
Y-657600D01*
X1194500Y-659200D01*
G01Y-665600D02*
X1196900D01*
G01X1202000Y-664667D02*
X1202700Y-665333D01*
X1203500Y-665600D01*
X1204300Y-665333D01*
X1205000Y-664534D01*
X1205500Y-663333D01*
X1205700Y-662133D01*
Y-660667D01*
X1205500Y-659467D01*
X1205000Y-658400D01*
X1204400Y-657867D01*
X1203700Y-657600D01*
X1202900Y-657867D01*
X1202300Y-658400D01*
X1201900Y-659200D01*
X1201700Y-660267D01*
X1201900Y-661200D01*
X1202400Y-662133D01*
X1203000Y-662667D01*
X1203700Y-662800D01*
X1204500Y-662534D01*
X1205100Y-661867D01*
X1205700Y-660667D01*
G01X1209800Y-662267D02*
X1210500Y-661333D01*
X1211100Y-660800D01*
X1211900Y-660533D01*
X1212600Y-660800D01*
X1213100Y-661333D01*
X1213500Y-662133D01*
X1213600Y-663067D01*
X1213500Y-663867D01*
X1213100Y-664667D01*
X1212500Y-665333D01*
X1211800Y-665600D01*
X1211000Y-665333D01*
X1210300Y-664534D01*
X1209900Y-663333D01*
X1209800Y-662000D01*
X1210000Y-660267D01*
X1210300Y-659333D01*
X1210800Y-658400D01*
X1211500Y-657733D01*
X1212200Y-657600D01*
X1212900Y-657867D01*
X1213400Y-658533D01*
G01X1219700Y-665600D02*
X1220400Y-665467D01*
X1221200Y-665067D01*
X1221700Y-664400D01*
X1221900Y-663467D01*
X1221700Y-662534D01*
X1221100Y-661733D01*
X1220200Y-661333D01*
X1219200D01*
X1218600Y-661067D01*
X1218100Y-660400D01*
X1217900Y-659467D01*
X1218200Y-658533D01*
X1218900Y-657867D01*
X1219700Y-657600D01*
X1220500Y-657867D01*
X1221200Y-658533D01*
X1221500Y-659467D01*
X1221300Y-660400D01*
X1220800Y-661067D01*
X1220200Y-661333D01*
X1219200D01*
X1218300Y-661733D01*
X1217700Y-662534D01*
X1217500Y-663467D01*
X1217700Y-664400D01*
X1218200Y-665067D01*
X1219000Y-665467D01*
X1219700Y-665600D01*
G01X1235700Y-660267D02*
Y-665600D01*
G01Y-658133D02*
X1235500Y-658000D01*
Y-657733D01*
X1235700Y-657600D01*
X1235900Y-657733D01*
Y-658000D01*
X1235700Y-658133D01*
G01X1242200Y-664667D02*
X1242700Y-665200D01*
X1243400Y-665600D01*
X1244000D01*
X1244600Y-665333D01*
X1245000Y-664933D01*
X1245200Y-664400D01*
X1245100Y-663600D01*
X1244700Y-663200D01*
X1242900Y-662400D01*
X1242500Y-661467D01*
X1242700Y-660800D01*
X1243100Y-660400D01*
X1243700Y-660267D01*
X1244300Y-660400D01*
X1244900Y-660800D01*
G01X1259700Y-665600D02*
Y-657600D01*
G01X1266200Y-662000D02*
X1269400D01*
X1269100Y-661067D01*
X1268600Y-660533D01*
X1267900Y-660267D01*
X1267200Y-660400D01*
X1266600Y-660800D01*
X1266200Y-661733D01*
X1266000Y-662534D01*
Y-663333D01*
X1266200Y-664133D01*
X1266700Y-664933D01*
X1267300Y-665467D01*
X1268000Y-665600D01*
X1268700Y-665333D01*
X1269400Y-664534D01*
G01X1274200Y-664667D02*
X1274700Y-665200D01*
X1275400Y-665600D01*
X1276000D01*
X1276600Y-665333D01*
X1277000Y-664933D01*
X1277200Y-664400D01*
X1277100Y-663600D01*
X1276700Y-663200D01*
X1274900Y-662400D01*
X1274500Y-661467D01*
X1274700Y-660800D01*
X1275100Y-660400D01*
X1275700Y-660267D01*
X1276300Y-660400D01*
X1276900Y-660800D01*
G01X1282200Y-664667D02*
X1282700Y-665200D01*
X1283400Y-665600D01*
X1284000D01*
X1284600Y-665333D01*
X1285000Y-664933D01*
X1285200Y-664400D01*
X1285100Y-663600D01*
X1284700Y-663200D01*
X1282900Y-662400D01*
X1282500Y-661467D01*
X1282700Y-660800D01*
X1283100Y-660400D01*
X1283700Y-660267D01*
X1284300Y-660400D01*
X1284900Y-660800D01*
G01X1299700Y-657600D02*
Y-665600D01*
G01X1298300Y-660267D02*
X1301100D01*
G01X1306000Y-665600D02*
Y-657600D01*
G01Y-661467D02*
X1306500Y-660800D01*
X1307000Y-660400D01*
X1307800Y-660267D01*
X1308400Y-660400D01*
X1309100Y-660933D01*
X1309400Y-661733D01*
Y-665600D01*
G01X1317500D02*
Y-660267D01*
G01Y-661200D02*
X1317100Y-660667D01*
X1316500Y-660400D01*
X1315800Y-660267D01*
X1315100Y-660533D01*
X1314500Y-661067D01*
X1314100Y-661867D01*
X1313900Y-662933D01*
X1314100Y-664000D01*
X1314500Y-664800D01*
X1315100Y-665333D01*
X1315800Y-665600D01*
X1316500Y-665467D01*
X1317100Y-665067D01*
X1317500Y-664534D01*
G01X1322000Y-665600D02*
Y-660267D01*
G01Y-661600D02*
X1322400Y-660933D01*
X1323000Y-660400D01*
X1323800Y-660267D01*
X1324500Y-660400D01*
X1325100Y-660933D01*
X1325400Y-661867D01*
Y-665600D01*
G01X1339700D02*
Y-657600D01*
X1338500Y-659200D01*
G01Y-665600D02*
X1340900D01*
G01X1352700D02*
Y-660267D01*
G01Y-661733D02*
X1353000Y-661067D01*
X1353500Y-660533D01*
X1354200Y-660267D01*
X1354900Y-660533D01*
X1355400Y-661067D01*
X1355700Y-661733D01*
Y-665600D01*
G01Y-661733D02*
X1356000Y-661067D01*
X1356500Y-660533D01*
X1357200Y-660267D01*
X1357900Y-660533D01*
X1358400Y-661067D01*
X1358700Y-661867D01*
Y-665600D01*
G01X1363700Y-660267D02*
Y-665600D01*
G01Y-658133D02*
X1363500Y-658000D01*
Y-657733D01*
X1363700Y-657600D01*
X1363900Y-657733D01*
Y-658000D01*
X1363700Y-658133D01*
G01X1371700Y-665600D02*
Y-657600D01*
G01X1379500Y-667067D02*
X1379900Y-665333D01*
G01X612600Y-484134D02*
X613400Y-484800D01*
X614300Y-485200D01*
X615100D01*
X615900Y-484800D01*
X616500Y-484134D01*
X616800Y-483200D01*
X616600Y-482267D01*
X616100Y-481467D01*
X615200Y-480933D01*
X614000Y-480667D01*
X613300Y-480133D01*
X613000Y-479200D01*
X613200Y-478267D01*
X613700Y-477600D01*
X614400Y-477200D01*
X615100D01*
X615800Y-477467D01*
X616400Y-478133D01*
G01X622700Y-479867D02*
Y-485200D01*
G01Y-477733D02*
X622500Y-477600D01*
Y-477333D01*
X622700Y-477200D01*
X622900Y-477333D01*
Y-477600D01*
X622700Y-477733D01*
G01X629200Y-479867D02*
X632200D01*
X629200Y-485200D01*
X632200D01*
G01X637200Y-481600D02*
X640400D01*
X640100Y-480667D01*
X639600Y-480133D01*
X638900Y-479867D01*
X638200Y-480000D01*
X637600Y-480400D01*
X637200Y-481333D01*
X637000Y-482134D01*
Y-482933D01*
X637200Y-483733D01*
X637700Y-484533D01*
X638300Y-485067D01*
X639000Y-485200D01*
X639700Y-484933D01*
X640400Y-484134D01*
G01X592200Y-428200D02*
X594700Y-420200D01*
X597200Y-428200D01*
G01X596300Y-425400D02*
X593100D01*
G01X602700Y-428200D02*
Y-420200D01*
G01X610700Y-422867D02*
Y-428200D01*
G01Y-420733D02*
X610500Y-420600D01*
Y-420333D01*
X610700Y-420200D01*
X610900Y-420333D01*
Y-420600D01*
X610700Y-420733D01*
G01X617300Y-430200D02*
X618000Y-430733D01*
X618800Y-430867D01*
X619500Y-430733D01*
X620100Y-430067D01*
X620500Y-429133D01*
Y-422867D01*
G01Y-423933D02*
X620100Y-423400D01*
X619500Y-423000D01*
X618800Y-422867D01*
X618000Y-423133D01*
X617500Y-423667D01*
X617100Y-424600D01*
X616900Y-425533D01*
X617000Y-426333D01*
X617400Y-427267D01*
X618000Y-427933D01*
X618800Y-428200D01*
X619400Y-428067D01*
X620100Y-427533D01*
X620500Y-427000D01*
G01X625000Y-428200D02*
Y-422867D01*
G01Y-424200D02*
X625400Y-423533D01*
X626000Y-423000D01*
X626800Y-422867D01*
X627500Y-423000D01*
X628100Y-423533D01*
X628400Y-424467D01*
Y-428200D01*
G01X631700D02*
Y-422867D01*
G01Y-424333D02*
X632000Y-423667D01*
X632500Y-423133D01*
X633200Y-422867D01*
X633900Y-423133D01*
X634400Y-423667D01*
X634700Y-424333D01*
Y-428200D01*
G01Y-424333D02*
X635000Y-423667D01*
X635500Y-423133D01*
X636200Y-422867D01*
X636900Y-423133D01*
X637400Y-423667D01*
X637700Y-424467D01*
Y-428200D01*
G01X641200Y-424600D02*
X644400D01*
X644100Y-423667D01*
X643600Y-423133D01*
X642900Y-422867D01*
X642200Y-423000D01*
X641600Y-423400D01*
X641200Y-424333D01*
X641000Y-425134D01*
Y-425933D01*
X641200Y-426733D01*
X641700Y-427533D01*
X642300Y-428067D01*
X643000Y-428200D01*
X643700Y-427933D01*
X644400Y-427134D01*
G01X649000Y-428200D02*
Y-422867D01*
G01Y-424200D02*
X649400Y-423533D01*
X650000Y-423000D01*
X650800Y-422867D01*
X651500Y-423000D01*
X652100Y-423533D01*
X652400Y-424467D01*
Y-428200D01*
G01X658700Y-420200D02*
Y-428200D01*
G01X657300Y-422867D02*
X660100D01*
G01X675100Y-576700D02*
Y-568700D01*
G01X679300D02*
Y-576700D01*
G01Y-572700D02*
X675100D01*
G01X685200Y-576700D02*
X684600Y-576567D01*
X684000Y-576033D01*
X683600Y-575100D01*
X683400Y-574033D01*
X683600Y-572967D01*
X684000Y-572033D01*
X684600Y-571500D01*
X685200Y-571367D01*
X685800Y-571500D01*
X686400Y-572033D01*
X686800Y-572967D01*
X686900Y-574033D01*
X686800Y-575100D01*
X686400Y-576033D01*
X685800Y-576567D01*
X685200Y-576700D01*
G01X693200D02*
Y-568700D01*
G01X699700Y-573100D02*
X702900D01*
X702600Y-572167D01*
X702100Y-571633D01*
X701400Y-571367D01*
X700700Y-571500D01*
X700100Y-571900D01*
X699700Y-572833D01*
X699500Y-573634D01*
Y-574433D01*
X699700Y-575233D01*
X700200Y-576033D01*
X700800Y-576567D01*
X701500Y-576700D01*
X702200Y-576433D01*
X702900Y-575634D01*
G01X714200Y-568700D02*
X715600Y-576700D01*
X717200Y-568700D01*
X718800Y-576700D01*
X720200Y-568700D01*
G01X727000Y-576700D02*
Y-571367D01*
G01Y-572300D02*
X726600Y-571767D01*
X726000Y-571500D01*
X725300Y-571367D01*
X724600Y-571633D01*
X724000Y-572167D01*
X723600Y-572967D01*
X723400Y-574033D01*
X723600Y-575100D01*
X724000Y-575900D01*
X724600Y-576433D01*
X725300Y-576700D01*
X726000Y-576567D01*
X726600Y-576167D01*
X727000Y-575634D01*
G01X733200Y-576700D02*
Y-568700D01*
G01X741200Y-576700D02*
Y-568700D01*
G01X755200Y-576700D02*
Y-568700D01*
X757700D01*
X758500Y-569100D01*
X759000Y-569633D01*
X759200Y-570700D01*
X759000Y-571767D01*
X758400Y-572433D01*
X757700Y-572833D01*
X755200D01*
G01X757700D02*
X759200Y-576700D01*
G01X765200D02*
X764600Y-576567D01*
X764000Y-576033D01*
X763600Y-575100D01*
X763400Y-574033D01*
X763600Y-572967D01*
X764000Y-572033D01*
X764600Y-571500D01*
X765200Y-571367D01*
X765800Y-571500D01*
X766400Y-572033D01*
X766800Y-572967D01*
X766900Y-574033D01*
X766800Y-575100D01*
X766400Y-576033D01*
X765800Y-576567D01*
X765200Y-576700D01*
G01X771500Y-571367D02*
Y-575100D01*
X771900Y-576033D01*
X772500Y-576567D01*
X773200Y-576700D01*
X773900Y-576567D01*
X774500Y-576033D01*
X774900Y-575100D01*
G01Y-576700D02*
Y-571367D01*
G01X779800Y-578700D02*
X780500Y-579233D01*
X781300Y-579367D01*
X782000Y-579233D01*
X782600Y-578567D01*
X783000Y-577633D01*
Y-571367D01*
G01Y-572433D02*
X782600Y-571900D01*
X782000Y-571500D01*
X781300Y-571367D01*
X780500Y-571633D01*
X780000Y-572167D01*
X779600Y-573100D01*
X779400Y-574033D01*
X779500Y-574833D01*
X779900Y-575767D01*
X780500Y-576433D01*
X781300Y-576700D01*
X781900Y-576567D01*
X782600Y-576033D01*
X783000Y-575500D01*
G01X787500Y-576700D02*
Y-568700D01*
G01Y-572567D02*
X788000Y-571900D01*
X788500Y-571500D01*
X789300Y-571367D01*
X789900Y-571500D01*
X790600Y-572033D01*
X790900Y-572833D01*
Y-576700D01*
G01X795500D02*
Y-571367D01*
G01Y-572700D02*
X795900Y-572033D01*
X796500Y-571500D01*
X797300Y-571367D01*
X798000Y-571500D01*
X798600Y-572033D01*
X798900Y-572967D01*
Y-576700D01*
G01X803700Y-573100D02*
X806900D01*
X806600Y-572167D01*
X806100Y-571633D01*
X805400Y-571367D01*
X804700Y-571500D01*
X804100Y-571900D01*
X803700Y-572833D01*
X803500Y-573634D01*
Y-574433D01*
X803700Y-575233D01*
X804200Y-576033D01*
X804800Y-576567D01*
X805500Y-576700D01*
X806200Y-576433D01*
X806900Y-575634D01*
G01X811700Y-575767D02*
X812200Y-576300D01*
X812900Y-576700D01*
X813500D01*
X814100Y-576433D01*
X814500Y-576033D01*
X814700Y-575500D01*
X814600Y-574700D01*
X814200Y-574300D01*
X812400Y-573500D01*
X812000Y-572567D01*
X812200Y-571900D01*
X812600Y-571500D01*
X813200Y-571367D01*
X813800Y-571500D01*
X814400Y-571900D01*
G01X819700Y-575767D02*
X820200Y-576300D01*
X820900Y-576700D01*
X821500D01*
X822100Y-576433D01*
X822500Y-576033D01*
X822700Y-575500D01*
X822600Y-574700D01*
X822200Y-574300D01*
X820400Y-573500D01*
X820000Y-572567D01*
X820200Y-571900D01*
X820600Y-571500D01*
X821200Y-571367D01*
X821800Y-571500D01*
X822400Y-571900D01*
G01X676200Y-564700D02*
X675400Y-564567D01*
X674700Y-564033D01*
X674100Y-563233D01*
X673700Y-562300D01*
X673500Y-561233D01*
Y-560167D01*
X673700Y-559100D01*
X674100Y-558167D01*
X674700Y-557367D01*
X675400Y-556833D01*
X676200Y-556700D01*
X677000Y-556833D01*
X677700Y-557367D01*
X678300Y-558167D01*
X678700Y-559100D01*
X678900Y-560167D01*
Y-561233D01*
X678700Y-562300D01*
X678300Y-563233D01*
X677700Y-564033D01*
X677000Y-564567D01*
X676200Y-564700D01*
G01X684200Y-556700D02*
Y-564700D01*
G01X682800Y-559367D02*
X685600D01*
G01X690500Y-564700D02*
Y-556700D01*
G01Y-560567D02*
X691000Y-559900D01*
X691500Y-559500D01*
X692300Y-559367D01*
X692900Y-559500D01*
X693600Y-560033D01*
X693900Y-560833D01*
Y-564700D01*
G01X698700Y-561100D02*
X701900D01*
X701600Y-560167D01*
X701100Y-559633D01*
X700400Y-559367D01*
X699700Y-559500D01*
X699100Y-559900D01*
X698700Y-560833D01*
X698500Y-561634D01*
Y-562433D01*
X698700Y-563233D01*
X699200Y-564033D01*
X699800Y-564567D01*
X700500Y-564700D01*
X701200Y-564433D01*
X701900Y-563634D01*
G01X706800Y-564700D02*
Y-559367D01*
G01Y-560433D02*
X707300Y-559900D01*
X707800Y-559500D01*
X708500Y-559367D01*
X709000Y-559500D01*
X709600Y-559900D01*
G01X714700Y-563767D02*
X715200Y-564300D01*
X715900Y-564700D01*
X716500D01*
X717100Y-564433D01*
X717500Y-564033D01*
X717700Y-563500D01*
X717600Y-562700D01*
X717200Y-562300D01*
X715400Y-561500D01*
X715000Y-560567D01*
X715200Y-559900D01*
X715600Y-559500D01*
X716200Y-559367D01*
X716800Y-559500D01*
X717400Y-559900D01*
G01X731700Y-567367D02*
X730700Y-566033D01*
X730200Y-564700D01*
Y-559367D01*
X730700Y-558033D01*
X731700Y-556700D01*
G01X740200Y-564700D02*
Y-556700D01*
G01X748200Y-559367D02*
Y-564700D01*
G01Y-557233D02*
X748000Y-557100D01*
Y-556833D01*
X748200Y-556700D01*
X748400Y-556833D01*
Y-557100D01*
X748200Y-557233D01*
G01X754500Y-564700D02*
Y-556700D01*
G01X757700Y-559367D02*
X754500Y-562433D01*
G01X755800Y-561233D02*
X757900Y-564700D01*
G01X762700Y-561100D02*
X765900D01*
X765600Y-560167D01*
X765100Y-559633D01*
X764400Y-559367D01*
X763700Y-559500D01*
X763100Y-559900D01*
X762700Y-560833D01*
X762500Y-561634D01*
Y-562433D01*
X762700Y-563233D01*
X763200Y-564033D01*
X763800Y-564567D01*
X764500Y-564700D01*
X765200Y-564433D01*
X765900Y-563634D01*
G01X778700Y-561100D02*
X781900D01*
X781600Y-560167D01*
X781100Y-559633D01*
X780400Y-559367D01*
X779700Y-559500D01*
X779100Y-559900D01*
X778700Y-560833D01*
X778500Y-561634D01*
Y-562433D01*
X778700Y-563233D01*
X779200Y-564033D01*
X779800Y-564567D01*
X780500Y-564700D01*
X781200Y-564433D01*
X781900Y-563634D01*
G01X788200Y-564700D02*
Y-556700D01*
G01X796200Y-564700D02*
Y-556700D01*
G01X804200Y-559367D02*
Y-564700D01*
G01Y-557233D02*
X804000Y-557100D01*
Y-556833D01*
X804200Y-556700D01*
X804400Y-556833D01*
Y-557100D01*
X804200Y-557233D01*
G01X810400Y-567367D02*
Y-559367D01*
G01Y-560567D02*
X810900Y-559900D01*
X811400Y-559500D01*
X812200Y-559367D01*
X812900Y-559500D01*
X813600Y-560167D01*
X813900Y-561100D01*
X814000Y-562033D01*
X813900Y-562967D01*
X813600Y-563900D01*
X813000Y-564433D01*
X812200Y-564700D01*
X811500Y-564567D01*
X810800Y-564167D01*
X810400Y-563634D01*
G01X818700Y-563767D02*
X819200Y-564300D01*
X819900Y-564700D01*
X820500D01*
X821100Y-564433D01*
X821500Y-564033D01*
X821700Y-563500D01*
X821600Y-562700D01*
X821200Y-562300D01*
X819400Y-561500D01*
X819000Y-560567D01*
X819200Y-559900D01*
X819600Y-559500D01*
X820200Y-559367D01*
X820800Y-559500D01*
X821400Y-559900D01*
G01X826700Y-561100D02*
X829900D01*
X829600Y-560167D01*
X829100Y-559633D01*
X828400Y-559367D01*
X827700Y-559500D01*
X827100Y-559900D01*
X826700Y-560833D01*
X826500Y-561634D01*
Y-562433D01*
X826700Y-563233D01*
X827200Y-564033D01*
X827800Y-564567D01*
X828500Y-564700D01*
X829200Y-564433D01*
X829900Y-563634D01*
G01X846000Y-564700D02*
Y-559367D01*
G01Y-560300D02*
X845600Y-559767D01*
X845000Y-559500D01*
X844300Y-559367D01*
X843600Y-559633D01*
X843000Y-560167D01*
X842600Y-560967D01*
X842400Y-562033D01*
X842600Y-563100D01*
X843000Y-563900D01*
X843600Y-564433D01*
X844300Y-564700D01*
X845000Y-564567D01*
X845600Y-564167D01*
X846000Y-563634D01*
G01X850500Y-564700D02*
Y-559367D01*
G01Y-560700D02*
X850900Y-560033D01*
X851500Y-559500D01*
X852300Y-559367D01*
X853000Y-559500D01*
X853600Y-560033D01*
X853900Y-560967D01*
Y-564700D01*
G01X862000Y-556700D02*
Y-564700D01*
G01Y-563500D02*
X861600Y-564167D01*
X861000Y-564567D01*
X860300Y-564700D01*
X859500Y-564433D01*
X858900Y-563767D01*
X858500Y-562967D01*
X858400Y-562033D01*
X858500Y-561100D01*
X858900Y-560300D01*
X859500Y-559633D01*
X860300Y-559367D01*
X861000Y-559500D01*
X861500Y-559767D01*
X862000Y-560300D01*
G01X876200Y-564700D02*
X875600Y-564567D01*
X875000Y-564033D01*
X874600Y-563100D01*
X874400Y-562033D01*
X874600Y-560967D01*
X875000Y-560033D01*
X875600Y-559500D01*
X876200Y-559367D01*
X876800Y-559500D01*
X877400Y-560033D01*
X877800Y-560967D01*
X877900Y-562033D01*
X877800Y-563100D01*
X877400Y-564033D01*
X876800Y-564567D01*
X876200Y-564700D01*
G01X884200Y-556700D02*
Y-564700D01*
G01X882800Y-559367D02*
X885600D01*
G01X890500Y-564700D02*
Y-556700D01*
G01Y-560567D02*
X891000Y-559900D01*
X891500Y-559500D01*
X892300Y-559367D01*
X892900Y-559500D01*
X893600Y-560033D01*
X893900Y-560833D01*
Y-564700D01*
G01X898700Y-561100D02*
X901900D01*
X901600Y-560167D01*
X901100Y-559633D01*
X900400Y-559367D01*
X899700Y-559500D01*
X899100Y-559900D01*
X898700Y-560833D01*
X898500Y-561634D01*
Y-562433D01*
X898700Y-563233D01*
X899200Y-564033D01*
X899800Y-564567D01*
X900500Y-564700D01*
X901200Y-564433D01*
X901900Y-563634D01*
G01X906800Y-564700D02*
Y-559367D01*
G01Y-560433D02*
X907300Y-559900D01*
X907800Y-559500D01*
X908500Y-559367D01*
X909000Y-559500D01*
X909600Y-559900D01*
G01X914700Y-563767D02*
X915200Y-564300D01*
X915900Y-564700D01*
X916500D01*
X917100Y-564433D01*
X917500Y-564033D01*
X917700Y-563500D01*
X917600Y-562700D01*
X917200Y-562300D01*
X915400Y-561500D01*
X915000Y-560567D01*
X915200Y-559900D01*
X915600Y-559500D01*
X916200Y-559367D01*
X916800Y-559500D01*
X917400Y-559900D01*
G01X924700Y-567367D02*
X925700Y-566033D01*
X926200Y-564700D01*
Y-559367D01*
X925700Y-558033D01*
X924700Y-556700D01*
G01X674200Y-553200D02*
Y-545200D01*
X676600D01*
X677400Y-545600D01*
X678000Y-546533D01*
X678200Y-547600D01*
X678000Y-548667D01*
X677500Y-549467D01*
X676600Y-549867D01*
X674200D01*
G01X684200Y-545200D02*
Y-553200D01*
G01X681900Y-545200D02*
X686500D01*
G01X690100Y-553200D02*
Y-545200D01*
G01X694300D02*
Y-553200D01*
G01Y-549200D02*
X690100D01*
G01X698400Y-553467D02*
X702000Y-545200D01*
G01X705900Y-553200D02*
Y-545200D01*
X710500Y-553200D01*
Y-545200D01*
G01X714200Y-553200D02*
Y-545200D01*
X716600D01*
X717400Y-545600D01*
X718000Y-546533D01*
X718200Y-547600D01*
X718000Y-548667D01*
X717500Y-549467D01*
X716600Y-549867D01*
X714200D01*
G01X724200Y-545200D02*
Y-553200D01*
G01X721900Y-545200D02*
X726500D01*
G01X730100Y-553200D02*
Y-545200D01*
G01X734300D02*
Y-553200D01*
G01Y-549200D02*
X730100D01*
G01X746200Y-553200D02*
X750200Y-550533D01*
X746200Y-547867D01*
G01X754900Y-551733D02*
X757500D01*
G01Y-549333D02*
X754900D01*
G01X762000Y-552000D02*
X762600Y-552667D01*
X763300Y-553067D01*
X764200Y-553200D01*
X765100Y-552933D01*
X765800Y-552400D01*
X766300Y-551467D01*
X766400Y-550400D01*
X766200Y-549333D01*
X765700Y-548667D01*
X765000Y-548133D01*
X764300Y-548000D01*
X763600Y-548133D01*
X762700Y-548667D01*
X763000Y-545200D01*
X765700D01*
G01X777200Y-553200D02*
Y-547867D01*
G01Y-549333D02*
X777500Y-548667D01*
X778000Y-548133D01*
X778700Y-547867D01*
X779400Y-548133D01*
X779900Y-548667D01*
X780200Y-549333D01*
Y-553200D01*
G01Y-549333D02*
X780500Y-548667D01*
X781000Y-548133D01*
X781700Y-547867D01*
X782400Y-548133D01*
X782900Y-548667D01*
X783200Y-549467D01*
Y-553200D01*
G01X785200D02*
Y-547867D01*
G01Y-549333D02*
X785500Y-548667D01*
X786000Y-548133D01*
X786700Y-547867D01*
X787400Y-548133D01*
X787900Y-548667D01*
X788200Y-549333D01*
Y-553200D01*
G01Y-549333D02*
X788500Y-548667D01*
X789000Y-548133D01*
X789700Y-547867D01*
X790400Y-548133D01*
X790900Y-548667D01*
X791200Y-549467D01*
Y-553200D01*
G01X674400Y-528200D02*
Y-520200D01*
X679000Y-528200D01*
Y-520200D01*
G01X682700Y-528200D02*
Y-520200D01*
X685100D01*
X685900Y-520600D01*
X686500Y-521533D01*
X686700Y-522600D01*
X686500Y-523667D01*
X686000Y-524467D01*
X685100Y-524867D01*
X682700D01*
G01X692700Y-520200D02*
Y-528200D01*
G01X690400Y-520200D02*
X695000D01*
G01X698600Y-528200D02*
Y-520200D01*
G01X702800D02*
Y-528200D01*
G01Y-524200D02*
X698600D01*
G01X714600Y-527134D02*
X715400Y-527800D01*
X716300Y-528200D01*
X717100D01*
X717900Y-527800D01*
X718500Y-527134D01*
X718800Y-526200D01*
X718600Y-525267D01*
X718100Y-524467D01*
X717200Y-523933D01*
X716000Y-523667D01*
X715300Y-523133D01*
X715000Y-522200D01*
X715200Y-521267D01*
X715700Y-520600D01*
X716400Y-520200D01*
X717100D01*
X717800Y-520467D01*
X718400Y-521133D01*
G01X724700Y-522867D02*
Y-528200D01*
G01Y-520733D02*
X724500Y-520600D01*
Y-520333D01*
X724700Y-520200D01*
X724900Y-520333D01*
Y-520600D01*
X724700Y-520733D01*
G01X731200Y-522867D02*
X734200D01*
X731200Y-528200D01*
X734200D01*
G01X739200Y-524600D02*
X742400D01*
X742100Y-523667D01*
X741600Y-523133D01*
X740900Y-522867D01*
X740200Y-523000D01*
X739600Y-523400D01*
X739200Y-524333D01*
X739000Y-525134D01*
Y-525933D01*
X739200Y-526733D01*
X739700Y-527533D01*
X740300Y-528067D01*
X741000Y-528200D01*
X741700Y-527933D01*
X742400Y-527134D01*
G01X754500Y-526600D02*
X755100Y-527533D01*
X755900Y-528067D01*
X756800Y-528200D01*
X757600Y-528067D01*
X758400Y-527400D01*
X758900Y-526600D01*
X759000Y-525800D01*
X758800Y-524867D01*
X758100Y-524200D01*
X757400Y-523933D01*
X756500D01*
G01X757400D02*
X758000Y-523533D01*
X758500Y-522867D01*
X758700Y-522067D01*
X758500Y-521267D01*
X758000Y-520600D01*
X757100Y-520200D01*
X756200Y-520333D01*
X755300Y-520867D01*
G01X764700Y-528467D02*
X764500Y-528333D01*
Y-528067D01*
X764700Y-527933D01*
X764900Y-528067D01*
Y-528333D01*
X764700Y-528467D01*
G01X770500Y-527000D02*
X771100Y-527667D01*
X771800Y-528067D01*
X772700Y-528200D01*
X773600Y-527933D01*
X774300Y-527400D01*
X774800Y-526467D01*
X774900Y-525400D01*
X774700Y-524333D01*
X774200Y-523667D01*
X773500Y-523133D01*
X772800Y-523000D01*
X772100Y-523133D01*
X771200Y-523667D01*
X771500Y-520200D01*
X774200D01*
G01X778500Y-527000D02*
X779100Y-527667D01*
X779800Y-528067D01*
X780700Y-528200D01*
X781600Y-527933D01*
X782300Y-527400D01*
X782800Y-526467D01*
X782900Y-525400D01*
X782700Y-524333D01*
X782200Y-523667D01*
X781500Y-523133D01*
X780800Y-523000D01*
X780100Y-523133D01*
X779200Y-523667D01*
X779500Y-520200D01*
X782200D01*
G01X785700Y-528200D02*
Y-522867D01*
G01Y-524333D02*
X786000Y-523667D01*
X786500Y-523133D01*
X787200Y-522867D01*
X787900Y-523133D01*
X788400Y-523667D01*
X788700Y-524333D01*
Y-528200D01*
G01Y-524333D02*
X789000Y-523667D01*
X789500Y-523133D01*
X790200Y-522867D01*
X790900Y-523133D01*
X791400Y-523667D01*
X791700Y-524467D01*
Y-528200D01*
G01X793700D02*
Y-522867D01*
G01Y-524333D02*
X794000Y-523667D01*
X794500Y-523133D01*
X795200Y-522867D01*
X795900Y-523133D01*
X796400Y-523667D01*
X796700Y-524333D01*
Y-528200D01*
G01Y-524333D02*
X797000Y-523667D01*
X797500Y-523133D01*
X798200Y-522867D01*
X798900Y-523133D01*
X799400Y-523667D01*
X799700Y-524467D01*
Y-528200D01*
G01X812200Y-530867D02*
X811200Y-529533D01*
X810700Y-528200D01*
Y-522867D01*
X811200Y-521533D01*
X812200Y-520200D01*
G01X820700Y-528200D02*
X820100Y-528067D01*
X819500Y-527533D01*
X819100Y-526600D01*
X818900Y-525533D01*
X819100Y-524467D01*
X819500Y-523533D01*
X820100Y-523000D01*
X820700Y-522867D01*
X821300Y-523000D01*
X821900Y-523533D01*
X822300Y-524467D01*
X822400Y-525533D01*
X822300Y-526600D01*
X821900Y-527533D01*
X821300Y-528067D01*
X820700Y-528200D01*
G01X827000D02*
Y-522867D01*
G01Y-524200D02*
X827400Y-523533D01*
X828000Y-523000D01*
X828800Y-522867D01*
X829500Y-523000D01*
X830100Y-523533D01*
X830400Y-524467D01*
Y-528200D01*
G01X842900D02*
Y-520200D01*
G01Y-524200D02*
X843400Y-523400D01*
X844000Y-523000D01*
X844600Y-522867D01*
X845500Y-523133D01*
X846100Y-523667D01*
X846500Y-524600D01*
Y-525667D01*
X846300Y-526733D01*
X845900Y-527533D01*
X845200Y-528067D01*
X844600Y-528200D01*
X844000Y-528067D01*
X843400Y-527667D01*
X842900Y-527000D01*
G01X851300Y-528200D02*
Y-522867D01*
G01Y-523933D02*
X851800Y-523400D01*
X852300Y-523000D01*
X853000Y-522867D01*
X853500Y-523000D01*
X854100Y-523400D01*
G01X859200Y-524600D02*
X862400D01*
X862100Y-523667D01*
X861600Y-523133D01*
X860900Y-522867D01*
X860200Y-523000D01*
X859600Y-523400D01*
X859200Y-524333D01*
X859000Y-525134D01*
Y-525933D01*
X859200Y-526733D01*
X859700Y-527533D01*
X860300Y-528067D01*
X861000Y-528200D01*
X861700Y-527933D01*
X862400Y-527134D01*
G01X870500Y-528200D02*
Y-522867D01*
G01Y-523800D02*
X870100Y-523267D01*
X869500Y-523000D01*
X868800Y-522867D01*
X868100Y-523133D01*
X867500Y-523667D01*
X867100Y-524467D01*
X866900Y-525533D01*
X867100Y-526600D01*
X867500Y-527400D01*
X868100Y-527933D01*
X868800Y-528200D01*
X869500Y-528067D01*
X870100Y-527667D01*
X870500Y-527134D01*
G01X875000Y-528200D02*
Y-520200D01*
G01X878200Y-522867D02*
X875000Y-525933D01*
G01X876300Y-524733D02*
X878400Y-528200D01*
G01X886500D02*
Y-522867D01*
G01Y-523800D02*
X886100Y-523267D01*
X885500Y-523000D01*
X884800Y-522867D01*
X884100Y-523133D01*
X883500Y-523667D01*
X883100Y-524467D01*
X882900Y-525533D01*
X883100Y-526600D01*
X883500Y-527400D01*
X884100Y-527933D01*
X884800Y-528200D01*
X885500Y-528067D01*
X886100Y-527667D01*
X886500Y-527134D01*
G01X890200Y-522867D02*
X891400Y-528200D01*
X892700Y-522867D01*
X894000Y-528200D01*
X895200Y-522867D01*
G01X902500Y-528200D02*
Y-522867D01*
G01Y-523800D02*
X902100Y-523267D01*
X901500Y-523000D01*
X900800Y-522867D01*
X900100Y-523133D01*
X899500Y-523667D01*
X899100Y-524467D01*
X898900Y-525533D01*
X899100Y-526600D01*
X899500Y-527400D01*
X900100Y-527933D01*
X900800Y-528200D01*
X901500Y-528067D01*
X902100Y-527667D01*
X902500Y-527134D01*
G01X906600Y-530600D02*
X907200Y-530867D01*
X908000Y-530600D01*
X908500Y-530067D01*
X908900Y-529400D01*
X909500Y-527267D01*
X910800Y-522867D01*
G01X907600D02*
X909500Y-527267D01*
G01X917200Y-530867D02*
X918200Y-529533D01*
X918700Y-528200D01*
Y-522867D01*
X918200Y-521533D01*
X917200Y-520200D01*
G01X674400Y-540200D02*
Y-532200D01*
X679000Y-540200D01*
Y-532200D01*
G01X682700Y-540200D02*
Y-532200D01*
X685100D01*
X685900Y-532600D01*
X686500Y-533533D01*
X686700Y-534600D01*
X686500Y-535667D01*
X686000Y-536467D01*
X685100Y-536867D01*
X682700D01*
G01X692700Y-532200D02*
Y-540200D01*
G01X690400Y-532200D02*
X695000D01*
G01X698600Y-540200D02*
Y-532200D01*
G01X702800D02*
Y-540200D01*
G01Y-536200D02*
X698600D01*
G01X714600Y-539134D02*
X715400Y-539800D01*
X716300Y-540200D01*
X717100D01*
X717900Y-539800D01*
X718500Y-539134D01*
X718800Y-538200D01*
X718600Y-537267D01*
X718100Y-536467D01*
X717200Y-535933D01*
X716000Y-535667D01*
X715300Y-535133D01*
X715000Y-534200D01*
X715200Y-533267D01*
X715700Y-532600D01*
X716400Y-532200D01*
X717100D01*
X717800Y-532467D01*
X718400Y-533133D01*
G01X724700Y-534867D02*
Y-540200D01*
G01Y-532733D02*
X724500Y-532600D01*
Y-532333D01*
X724700Y-532200D01*
X724900Y-532333D01*
Y-532600D01*
X724700Y-532733D01*
G01X731200Y-534867D02*
X734200D01*
X731200Y-540200D01*
X734200D01*
G01X739200Y-536600D02*
X742400D01*
X742100Y-535667D01*
X741600Y-535133D01*
X740900Y-534867D01*
X740200Y-535000D01*
X739600Y-535400D01*
X739200Y-536333D01*
X739000Y-537134D01*
Y-537933D01*
X739200Y-538733D01*
X739700Y-539533D01*
X740300Y-540067D01*
X741000Y-540200D01*
X741700Y-539933D01*
X742400Y-539134D01*
G01X754800Y-533533D02*
X755400Y-532733D01*
X756100Y-532333D01*
X756900Y-532200D01*
X757900Y-532467D01*
X758600Y-533133D01*
X758800Y-533933D01*
X758700Y-534734D01*
X758300Y-535400D01*
X756300Y-536733D01*
X755400Y-537667D01*
X754800Y-539000D01*
X754600Y-540200D01*
X758800D01*
G01X764700Y-540467D02*
X764500Y-540333D01*
Y-540067D01*
X764700Y-539933D01*
X764900Y-540067D01*
Y-540333D01*
X764700Y-540467D01*
G01X772700Y-540200D02*
Y-532200D01*
X771500Y-533800D01*
G01Y-540200D02*
X773900D01*
G01X780700D02*
X781400Y-540067D01*
X782200Y-539667D01*
X782700Y-539000D01*
X782900Y-538067D01*
X782700Y-537134D01*
X782100Y-536333D01*
X781200Y-535933D01*
X780200D01*
X779600Y-535667D01*
X779100Y-535000D01*
X778900Y-534067D01*
X779200Y-533133D01*
X779900Y-532467D01*
X780700Y-532200D01*
X781500Y-532467D01*
X782200Y-533133D01*
X782500Y-534067D01*
X782300Y-535000D01*
X781800Y-535667D01*
X781200Y-535933D01*
X780200D01*
X779300Y-536333D01*
X778700Y-537134D01*
X778500Y-538067D01*
X778700Y-539000D01*
X779200Y-539667D01*
X780000Y-540067D01*
X780700Y-540200D01*
G01X785700D02*
Y-534867D01*
G01Y-536333D02*
X786000Y-535667D01*
X786500Y-535133D01*
X787200Y-534867D01*
X787900Y-535133D01*
X788400Y-535667D01*
X788700Y-536333D01*
Y-540200D01*
G01Y-536333D02*
X789000Y-535667D01*
X789500Y-535133D01*
X790200Y-534867D01*
X790900Y-535133D01*
X791400Y-535667D01*
X791700Y-536467D01*
Y-540200D01*
G01X793700D02*
Y-534867D01*
G01Y-536333D02*
X794000Y-535667D01*
X794500Y-535133D01*
X795200Y-534867D01*
X795900Y-535133D01*
X796400Y-535667D01*
X796700Y-536333D01*
Y-540200D01*
G01Y-536333D02*
X797000Y-535667D01*
X797500Y-535133D01*
X798200Y-534867D01*
X798900Y-535133D01*
X799400Y-535667D01*
X799700Y-536467D01*
Y-540200D01*
G01X812200Y-542867D02*
X811200Y-541533D01*
X810700Y-540200D01*
Y-534867D01*
X811200Y-533533D01*
X812200Y-532200D01*
G01X820700Y-540200D02*
X820100Y-540067D01*
X819500Y-539533D01*
X819100Y-538600D01*
X818900Y-537533D01*
X819100Y-536467D01*
X819500Y-535533D01*
X820100Y-535000D01*
X820700Y-534867D01*
X821300Y-535000D01*
X821900Y-535533D01*
X822300Y-536467D01*
X822400Y-537533D01*
X822300Y-538600D01*
X821900Y-539533D01*
X821300Y-540067D01*
X820700Y-540200D01*
G01X827000D02*
Y-534867D01*
G01Y-536200D02*
X827400Y-535533D01*
X828000Y-535000D01*
X828800Y-534867D01*
X829500Y-535000D01*
X830100Y-535533D01*
X830400Y-536467D01*
Y-540200D01*
G01X842900D02*
Y-532200D01*
G01Y-536200D02*
X843400Y-535400D01*
X844000Y-535000D01*
X844600Y-534867D01*
X845500Y-535133D01*
X846100Y-535667D01*
X846500Y-536600D01*
Y-537667D01*
X846300Y-538733D01*
X845900Y-539533D01*
X845200Y-540067D01*
X844600Y-540200D01*
X844000Y-540067D01*
X843400Y-539667D01*
X842900Y-539000D01*
G01X851300Y-540200D02*
Y-534867D01*
G01Y-535933D02*
X851800Y-535400D01*
X852300Y-535000D01*
X853000Y-534867D01*
X853500Y-535000D01*
X854100Y-535400D01*
G01X859200Y-536600D02*
X862400D01*
X862100Y-535667D01*
X861600Y-535133D01*
X860900Y-534867D01*
X860200Y-535000D01*
X859600Y-535400D01*
X859200Y-536333D01*
X859000Y-537134D01*
Y-537933D01*
X859200Y-538733D01*
X859700Y-539533D01*
X860300Y-540067D01*
X861000Y-540200D01*
X861700Y-539933D01*
X862400Y-539134D01*
G01X870500Y-540200D02*
Y-534867D01*
G01Y-535800D02*
X870100Y-535267D01*
X869500Y-535000D01*
X868800Y-534867D01*
X868100Y-535133D01*
X867500Y-535667D01*
X867100Y-536467D01*
X866900Y-537533D01*
X867100Y-538600D01*
X867500Y-539400D01*
X868100Y-539933D01*
X868800Y-540200D01*
X869500Y-540067D01*
X870100Y-539667D01*
X870500Y-539134D01*
G01X875000Y-540200D02*
Y-532200D01*
G01X878200Y-534867D02*
X875000Y-537933D01*
G01X876300Y-536733D02*
X878400Y-540200D01*
G01X886500D02*
Y-534867D01*
G01Y-535800D02*
X886100Y-535267D01*
X885500Y-535000D01*
X884800Y-534867D01*
X884100Y-535133D01*
X883500Y-535667D01*
X883100Y-536467D01*
X882900Y-537533D01*
X883100Y-538600D01*
X883500Y-539400D01*
X884100Y-539933D01*
X884800Y-540200D01*
X885500Y-540067D01*
X886100Y-539667D01*
X886500Y-539134D01*
G01X890200Y-534867D02*
X891400Y-540200D01*
X892700Y-534867D01*
X894000Y-540200D01*
X895200Y-534867D01*
G01X902500Y-540200D02*
Y-534867D01*
G01Y-535800D02*
X902100Y-535267D01*
X901500Y-535000D01*
X900800Y-534867D01*
X900100Y-535133D01*
X899500Y-535667D01*
X899100Y-536467D01*
X898900Y-537533D01*
X899100Y-538600D01*
X899500Y-539400D01*
X900100Y-539933D01*
X900800Y-540200D01*
X901500Y-540067D01*
X902100Y-539667D01*
X902500Y-539134D01*
G01X906600Y-542600D02*
X907200Y-542867D01*
X908000Y-542600D01*
X908500Y-542067D01*
X908900Y-541400D01*
X909500Y-539267D01*
X910800Y-534867D01*
G01X907600D02*
X909500Y-539267D01*
G01X917200Y-542867D02*
X918200Y-541533D01*
X918700Y-540200D01*
Y-534867D01*
X918200Y-533533D01*
X917200Y-532200D01*
G01X674400Y-514700D02*
Y-506700D01*
X679000Y-514700D01*
Y-506700D01*
G01X682700Y-514700D02*
Y-506700D01*
X685100D01*
X685900Y-507100D01*
X686500Y-508033D01*
X686700Y-509100D01*
X686500Y-510167D01*
X686000Y-510967D01*
X685100Y-511367D01*
X682700D01*
G01X692700Y-506700D02*
Y-514700D01*
G01X690400Y-506700D02*
X695000D01*
G01X698600Y-514700D02*
Y-506700D01*
G01X702800D02*
Y-514700D01*
G01Y-510700D02*
X698600D01*
G01X714600Y-513634D02*
X715400Y-514300D01*
X716300Y-514700D01*
X717100D01*
X717900Y-514300D01*
X718500Y-513634D01*
X718800Y-512700D01*
X718600Y-511767D01*
X718100Y-510967D01*
X717200Y-510433D01*
X716000Y-510167D01*
X715300Y-509633D01*
X715000Y-508700D01*
X715200Y-507767D01*
X715700Y-507100D01*
X716400Y-506700D01*
X717100D01*
X717800Y-506967D01*
X718400Y-507633D01*
G01X724700Y-509367D02*
Y-514700D01*
G01Y-507233D02*
X724500Y-507100D01*
Y-506833D01*
X724700Y-506700D01*
X724900Y-506833D01*
Y-507100D01*
X724700Y-507233D01*
G01X731200Y-509367D02*
X734200D01*
X731200Y-514700D01*
X734200D01*
G01X739200Y-511100D02*
X742400D01*
X742100Y-510167D01*
X741600Y-509633D01*
X740900Y-509367D01*
X740200Y-509500D01*
X739600Y-509900D01*
X739200Y-510833D01*
X739000Y-511634D01*
Y-512433D01*
X739200Y-513233D01*
X739700Y-514033D01*
X740300Y-514567D01*
X741000Y-514700D01*
X741700Y-514433D01*
X742400Y-513634D01*
G01X750700Y-514700D02*
X746700Y-512033D01*
X750700Y-509367D01*
G01X762500Y-513500D02*
X763100Y-514167D01*
X763800Y-514567D01*
X764700Y-514700D01*
X765600Y-514433D01*
X766300Y-513900D01*
X766800Y-512967D01*
X766900Y-511900D01*
X766700Y-510833D01*
X766200Y-510167D01*
X765500Y-509633D01*
X764800Y-509500D01*
X764100Y-509633D01*
X763200Y-510167D01*
X763500Y-506700D01*
X766200D01*
G01X769700Y-514700D02*
Y-509367D01*
G01Y-510833D02*
X770000Y-510167D01*
X770500Y-509633D01*
X771200Y-509367D01*
X771900Y-509633D01*
X772400Y-510167D01*
X772700Y-510833D01*
Y-514700D01*
G01Y-510833D02*
X773000Y-510167D01*
X773500Y-509633D01*
X774200Y-509367D01*
X774900Y-509633D01*
X775400Y-510167D01*
X775700Y-510967D01*
Y-514700D01*
G01X777700D02*
Y-509367D01*
G01Y-510833D02*
X778000Y-510167D01*
X778500Y-509633D01*
X779200Y-509367D01*
X779900Y-509633D01*
X780400Y-510167D01*
X780700Y-510833D01*
Y-514700D01*
G01Y-510833D02*
X781000Y-510167D01*
X781500Y-509633D01*
X782200Y-509367D01*
X782900Y-509633D01*
X783400Y-510167D01*
X783700Y-510967D01*
Y-514700D01*
G01X796200Y-517367D02*
X795200Y-516033D01*
X794700Y-514700D01*
Y-509367D01*
X795200Y-508033D01*
X796200Y-506700D01*
G01X803000Y-514700D02*
Y-509367D01*
G01Y-510700D02*
X803400Y-510033D01*
X804000Y-509500D01*
X804800Y-509367D01*
X805500Y-509500D01*
X806100Y-510033D01*
X806400Y-510967D01*
Y-514700D01*
G01X812700D02*
X812100Y-514567D01*
X811500Y-514033D01*
X811100Y-513100D01*
X810900Y-512033D01*
X811100Y-510967D01*
X811500Y-510033D01*
X812100Y-509500D01*
X812700Y-509367D01*
X813300Y-509500D01*
X813900Y-510033D01*
X814300Y-510967D01*
X814400Y-512033D01*
X814300Y-513100D01*
X813900Y-514033D01*
X813300Y-514567D01*
X812700Y-514700D01*
G01X820700Y-506700D02*
Y-514700D01*
G01X819300Y-509367D02*
X822100D01*
G01X836700Y-514700D02*
X836100Y-514567D01*
X835500Y-514033D01*
X835100Y-513100D01*
X834900Y-512033D01*
X835100Y-510967D01*
X835500Y-510033D01*
X836100Y-509500D01*
X836700Y-509367D01*
X837300Y-509500D01*
X837900Y-510033D01*
X838300Y-510967D01*
X838400Y-512033D01*
X838300Y-513100D01*
X837900Y-514033D01*
X837300Y-514567D01*
X836700Y-514700D01*
G01X843000D02*
Y-509367D01*
G01Y-510700D02*
X843400Y-510033D01*
X844000Y-509500D01*
X844800Y-509367D01*
X845500Y-509500D01*
X846100Y-510033D01*
X846400Y-510967D01*
Y-514700D01*
G01X858900D02*
Y-506700D01*
G01Y-510700D02*
X859400Y-509900D01*
X860000Y-509500D01*
X860600Y-509367D01*
X861500Y-509633D01*
X862100Y-510167D01*
X862500Y-511100D01*
Y-512167D01*
X862300Y-513233D01*
X861900Y-514033D01*
X861200Y-514567D01*
X860600Y-514700D01*
X860000Y-514567D01*
X859400Y-514167D01*
X858900Y-513500D01*
G01X867300Y-514700D02*
Y-509367D01*
G01Y-510433D02*
X867800Y-509900D01*
X868300Y-509500D01*
X869000Y-509367D01*
X869500Y-509500D01*
X870100Y-509900D01*
G01X875200Y-511100D02*
X878400D01*
X878100Y-510167D01*
X877600Y-509633D01*
X876900Y-509367D01*
X876200Y-509500D01*
X875600Y-509900D01*
X875200Y-510833D01*
X875000Y-511634D01*
Y-512433D01*
X875200Y-513233D01*
X875700Y-514033D01*
X876300Y-514567D01*
X877000Y-514700D01*
X877700Y-514433D01*
X878400Y-513634D01*
G01X886500Y-514700D02*
Y-509367D01*
G01Y-510300D02*
X886100Y-509767D01*
X885500Y-509500D01*
X884800Y-509367D01*
X884100Y-509633D01*
X883500Y-510167D01*
X883100Y-510967D01*
X882900Y-512033D01*
X883100Y-513100D01*
X883500Y-513900D01*
X884100Y-514433D01*
X884800Y-514700D01*
X885500Y-514567D01*
X886100Y-514167D01*
X886500Y-513634D01*
G01X891000Y-514700D02*
Y-506700D01*
G01X894200Y-509367D02*
X891000Y-512433D01*
G01X892300Y-511233D02*
X894400Y-514700D01*
G01X902500D02*
Y-509367D01*
G01Y-510300D02*
X902100Y-509767D01*
X901500Y-509500D01*
X900800Y-509367D01*
X900100Y-509633D01*
X899500Y-510167D01*
X899100Y-510967D01*
X898900Y-512033D01*
X899100Y-513100D01*
X899500Y-513900D01*
X900100Y-514433D01*
X900800Y-514700D01*
X901500Y-514567D01*
X902100Y-514167D01*
X902500Y-513634D01*
G01X906200Y-509367D02*
X907400Y-514700D01*
X908700Y-509367D01*
X910000Y-514700D01*
X911200Y-509367D01*
G01X918500Y-514700D02*
Y-509367D01*
G01Y-510300D02*
X918100Y-509767D01*
X917500Y-509500D01*
X916800Y-509367D01*
X916100Y-509633D01*
X915500Y-510167D01*
X915100Y-510967D01*
X914900Y-512033D01*
X915100Y-513100D01*
X915500Y-513900D01*
X916100Y-514433D01*
X916800Y-514700D01*
X917500Y-514567D01*
X918100Y-514167D01*
X918500Y-513634D01*
G01X922600Y-517100D02*
X923200Y-517367D01*
X924000Y-517100D01*
X924500Y-516567D01*
X924900Y-515900D01*
X925500Y-513767D01*
X926800Y-509367D01*
G01X923600D02*
X925500Y-513767D01*
G01X933200Y-517367D02*
X934200Y-516033D01*
X934700Y-514700D01*
Y-509367D01*
X934200Y-508033D01*
X933200Y-506700D01*
G01X675200Y-503367D02*
X674200Y-502033D01*
X673700Y-500700D01*
Y-495367D01*
X674200Y-494033D01*
X675200Y-492700D01*
G01X681600Y-499634D02*
X682400Y-500300D01*
X683300Y-500700D01*
X684100D01*
X684900Y-500300D01*
X685500Y-499634D01*
X685800Y-498700D01*
X685600Y-497767D01*
X685100Y-496967D01*
X684200Y-496433D01*
X683000Y-496167D01*
X682300Y-495633D01*
X682000Y-494700D01*
X682200Y-493767D01*
X682700Y-493100D01*
X683400Y-492700D01*
X684100D01*
X684800Y-492967D01*
X685400Y-493633D01*
G01X690000Y-495367D02*
Y-499100D01*
X690400Y-500033D01*
X691000Y-500567D01*
X691700Y-500700D01*
X692400Y-500567D01*
X693000Y-500033D01*
X693400Y-499100D01*
G01Y-500700D02*
Y-495367D01*
G01X698300Y-500700D02*
Y-495367D01*
G01Y-496433D02*
X698800Y-495900D01*
X699300Y-495500D01*
X700000Y-495367D01*
X700500Y-495500D01*
X701100Y-495900D01*
G01X707100Y-500700D02*
Y-493900D01*
X707300Y-493233D01*
X707700Y-492833D01*
X708300Y-492700D01*
X708900Y-492967D01*
X709200Y-493633D01*
G01X708000Y-495900D02*
X706000D01*
G01X717500Y-500700D02*
Y-495367D01*
G01Y-496300D02*
X717100Y-495767D01*
X716500Y-495500D01*
X715800Y-495367D01*
X715100Y-495633D01*
X714500Y-496167D01*
X714100Y-496967D01*
X713900Y-498033D01*
X714100Y-499100D01*
X714500Y-499900D01*
X715100Y-500433D01*
X715800Y-500700D01*
X716500Y-500567D01*
X717100Y-500167D01*
X717500Y-499634D01*
G01X725300Y-496033D02*
X724600Y-495500D01*
X724000Y-495367D01*
X723200Y-495633D01*
X722600Y-496167D01*
X722200Y-497100D01*
X722100Y-498033D01*
X722200Y-498967D01*
X722600Y-499767D01*
X723200Y-500433D01*
X724000Y-500700D01*
X724700Y-500433D01*
X725300Y-499900D01*
G01X730200Y-497100D02*
X733400D01*
X733100Y-496167D01*
X732600Y-495633D01*
X731900Y-495367D01*
X731200Y-495500D01*
X730600Y-495900D01*
X730200Y-496833D01*
X730000Y-497634D01*
Y-498433D01*
X730200Y-499233D01*
X730700Y-500033D01*
X731300Y-500567D01*
X732000Y-500700D01*
X732700Y-500433D01*
X733400Y-499634D01*
G01X747700Y-492700D02*
Y-500700D01*
G01X746300Y-495367D02*
X749100D01*
G01X754300Y-500700D02*
Y-495367D01*
G01Y-496433D02*
X754800Y-495900D01*
X755300Y-495500D01*
X756000Y-495367D01*
X756500Y-495500D01*
X757100Y-495900D01*
G01X762200Y-497100D02*
X765400D01*
X765100Y-496167D01*
X764600Y-495633D01*
X763900Y-495367D01*
X763200Y-495500D01*
X762600Y-495900D01*
X762200Y-496833D01*
X762000Y-497634D01*
Y-498433D01*
X762200Y-499233D01*
X762700Y-500033D01*
X763300Y-500567D01*
X764000Y-500700D01*
X764700Y-500433D01*
X765400Y-499634D01*
G01X773500Y-500700D02*
Y-495367D01*
G01Y-496300D02*
X773100Y-495767D01*
X772500Y-495500D01*
X771800Y-495367D01*
X771100Y-495633D01*
X770500Y-496167D01*
X770100Y-496967D01*
X769900Y-498033D01*
X770100Y-499100D01*
X770500Y-499900D01*
X771100Y-500433D01*
X771800Y-500700D01*
X772500Y-500567D01*
X773100Y-500167D01*
X773500Y-499634D01*
G01X779700Y-492700D02*
Y-500700D01*
G01X778300Y-495367D02*
X781100D01*
G01X784700Y-500700D02*
Y-495367D01*
G01Y-496833D02*
X785000Y-496167D01*
X785500Y-495633D01*
X786200Y-495367D01*
X786900Y-495633D01*
X787400Y-496167D01*
X787700Y-496833D01*
Y-500700D01*
G01Y-496833D02*
X788000Y-496167D01*
X788500Y-495633D01*
X789200Y-495367D01*
X789900Y-495633D01*
X790400Y-496167D01*
X790700Y-496967D01*
Y-500700D01*
G01X794200Y-497100D02*
X797400D01*
X797100Y-496167D01*
X796600Y-495633D01*
X795900Y-495367D01*
X795200Y-495500D01*
X794600Y-495900D01*
X794200Y-496833D01*
X794000Y-497634D01*
Y-498433D01*
X794200Y-499233D01*
X794700Y-500033D01*
X795300Y-500567D01*
X796000Y-500700D01*
X796700Y-500433D01*
X797400Y-499634D01*
G01X802000Y-500700D02*
Y-495367D01*
G01Y-496700D02*
X802400Y-496033D01*
X803000Y-495500D01*
X803800Y-495367D01*
X804500Y-495500D01*
X805100Y-496033D01*
X805400Y-496967D01*
Y-500700D01*
G01X811700Y-492700D02*
Y-500700D01*
G01X810300Y-495367D02*
X813100D01*
G01X827700D02*
Y-500700D01*
G01Y-493233D02*
X827500Y-493100D01*
Y-492833D01*
X827700Y-492700D01*
X827900Y-492833D01*
Y-493100D01*
X827700Y-493233D01*
G01X834200Y-499767D02*
X834700Y-500300D01*
X835400Y-500700D01*
X836000D01*
X836600Y-500433D01*
X837000Y-500033D01*
X837200Y-499500D01*
X837100Y-498700D01*
X836700Y-498300D01*
X834900Y-497500D01*
X834500Y-496567D01*
X834700Y-495900D01*
X835100Y-495500D01*
X835700Y-495367D01*
X836300Y-495500D01*
X836900Y-495900D01*
G01X849600Y-500700D02*
Y-492700D01*
G01X853800D02*
Y-500700D01*
G01Y-496700D02*
X849600D01*
G01X857200Y-500700D02*
X859700Y-492700D01*
X862200Y-500700D01*
G01X861300Y-497900D02*
X858100D01*
G01X865600Y-499634D02*
X866400Y-500300D01*
X867300Y-500700D01*
X868100D01*
X868900Y-500300D01*
X869500Y-499634D01*
X869800Y-498700D01*
X869600Y-497767D01*
X869100Y-496967D01*
X868200Y-496433D01*
X867000Y-496167D01*
X866300Y-495633D01*
X866000Y-494700D01*
X866200Y-493767D01*
X866700Y-493100D01*
X867400Y-492700D01*
X868100D01*
X868800Y-492967D01*
X869400Y-493633D01*
G01X873700Y-492700D02*
Y-500700D01*
X877700D01*
G01X891700D02*
X891100Y-500567D01*
X890500Y-500033D01*
X890100Y-499100D01*
X889900Y-498033D01*
X890100Y-496967D01*
X890500Y-496033D01*
X891100Y-495500D01*
X891700Y-495367D01*
X892300Y-495500D01*
X892900Y-496033D01*
X893300Y-496967D01*
X893400Y-498033D01*
X893300Y-499100D01*
X892900Y-500033D01*
X892300Y-500567D01*
X891700Y-500700D01*
G01X898300D02*
Y-495367D01*
G01Y-496433D02*
X898800Y-495900D01*
X899300Y-495500D01*
X900000Y-495367D01*
X900500Y-495500D01*
X901100Y-495900D01*
G01X913700Y-492700D02*
Y-500700D01*
X917700D01*
G01X922200Y-497100D02*
X925400D01*
X925100Y-496167D01*
X924600Y-495633D01*
X923900Y-495367D01*
X923200Y-495500D01*
X922600Y-495900D01*
X922200Y-496833D01*
X922000Y-497634D01*
Y-498433D01*
X922200Y-499233D01*
X922700Y-500033D01*
X923300Y-500567D01*
X924000Y-500700D01*
X924700Y-500433D01*
X925400Y-499634D01*
G01X933500Y-500700D02*
Y-495367D01*
G01Y-496300D02*
X933100Y-495767D01*
X932500Y-495500D01*
X931800Y-495367D01*
X931100Y-495633D01*
X930500Y-496167D01*
X930100Y-496967D01*
X929900Y-498033D01*
X930100Y-499100D01*
X930500Y-499900D01*
X931100Y-500433D01*
X931800Y-500700D01*
X932500Y-500567D01*
X933100Y-500167D01*
X933500Y-499634D01*
G01X941500Y-492700D02*
Y-500700D01*
G01Y-499500D02*
X941100Y-500167D01*
X940500Y-500567D01*
X939800Y-500700D01*
X939000Y-500433D01*
X938400Y-499767D01*
X938000Y-498967D01*
X937900Y-498033D01*
X938000Y-497100D01*
X938400Y-496300D01*
X939000Y-495633D01*
X939800Y-495367D01*
X940500Y-495500D01*
X941000Y-495767D01*
X941500Y-496300D01*
G01X953800Y-500700D02*
Y-492700D01*
X957600D01*
G01X956200Y-496567D02*
X953800D01*
G01X962300Y-500700D02*
Y-495367D01*
G01Y-496433D02*
X962800Y-495900D01*
X963300Y-495500D01*
X964000Y-495367D01*
X964500Y-495500D01*
X965100Y-495900D01*
G01X970200Y-497100D02*
X973400D01*
X973100Y-496167D01*
X972600Y-495633D01*
X971900Y-495367D01*
X971200Y-495500D01*
X970600Y-495900D01*
X970200Y-496833D01*
X970000Y-497634D01*
Y-498433D01*
X970200Y-499233D01*
X970700Y-500033D01*
X971300Y-500567D01*
X972000Y-500700D01*
X972700Y-500433D01*
X973400Y-499634D01*
G01X978200Y-497100D02*
X981400D01*
X981100Y-496167D01*
X980600Y-495633D01*
X979900Y-495367D01*
X979200Y-495500D01*
X978600Y-495900D01*
X978200Y-496833D01*
X978000Y-497634D01*
Y-498433D01*
X978200Y-499233D01*
X978700Y-500033D01*
X979300Y-500567D01*
X980000Y-500700D01*
X980700Y-500433D01*
X981400Y-499634D01*
G01X993600Y-500700D02*
Y-492700D01*
G01X997800D02*
Y-500700D01*
G01Y-496700D02*
X993600D01*
G01X1001200Y-500700D02*
X1003700Y-492700D01*
X1006200Y-500700D01*
G01X1005300Y-497900D02*
X1002100D01*
G01X1009600Y-499634D02*
X1010400Y-500300D01*
X1011300Y-500700D01*
X1012100D01*
X1012900Y-500300D01*
X1013500Y-499634D01*
X1013800Y-498700D01*
X1013600Y-497767D01*
X1013100Y-496967D01*
X1012200Y-496433D01*
X1011000Y-496167D01*
X1010300Y-495633D01*
X1010000Y-494700D01*
X1010200Y-493767D01*
X1010700Y-493100D01*
X1011400Y-492700D01*
X1012100D01*
X1012800Y-492967D01*
X1013400Y-493633D01*
G01X1017700Y-492700D02*
Y-500700D01*
X1021700D01*
G01X1028200Y-503367D02*
X1029200Y-502033D01*
X1029700Y-500700D01*
Y-495367D01*
X1029200Y-494033D01*
X1028200Y-492700D01*
G01X674200Y-480367D02*
X673200Y-479033D01*
X672700Y-477700D01*
Y-472367D01*
X673200Y-471033D01*
X674200Y-469700D01*
G01X680600Y-476634D02*
X681400Y-477300D01*
X682300Y-477700D01*
X683100D01*
X683900Y-477300D01*
X684500Y-476634D01*
X684800Y-475700D01*
X684600Y-474767D01*
X684100Y-473967D01*
X683200Y-473433D01*
X682000Y-473167D01*
X681300Y-472633D01*
X681000Y-471700D01*
X681200Y-470767D01*
X681700Y-470100D01*
X682400Y-469700D01*
X683100D01*
X683800Y-469967D01*
X684400Y-470633D01*
G01X689000Y-472367D02*
Y-476100D01*
X689400Y-477033D01*
X690000Y-477567D01*
X690700Y-477700D01*
X691400Y-477567D01*
X692000Y-477033D01*
X692400Y-476100D01*
G01Y-477700D02*
Y-472367D01*
G01X697300Y-477700D02*
Y-472367D01*
G01Y-473433D02*
X697800Y-472900D01*
X698300Y-472500D01*
X699000Y-472367D01*
X699500Y-472500D01*
X700100Y-472900D01*
G01X706100Y-477700D02*
Y-470900D01*
X706300Y-470233D01*
X706700Y-469833D01*
X707300Y-469700D01*
X707900Y-469967D01*
X708200Y-470633D01*
G01X707000Y-472900D02*
X705000D01*
G01X716500Y-477700D02*
Y-472367D01*
G01Y-473300D02*
X716100Y-472767D01*
X715500Y-472500D01*
X714800Y-472367D01*
X714100Y-472633D01*
X713500Y-473167D01*
X713100Y-473967D01*
X712900Y-475033D01*
X713100Y-476100D01*
X713500Y-476900D01*
X714100Y-477433D01*
X714800Y-477700D01*
X715500Y-477567D01*
X716100Y-477167D01*
X716500Y-476634D01*
G01X724300Y-473033D02*
X723600Y-472500D01*
X723000Y-472367D01*
X722200Y-472633D01*
X721600Y-473167D01*
X721200Y-474100D01*
X721100Y-475033D01*
X721200Y-475967D01*
X721600Y-476767D01*
X722200Y-477433D01*
X723000Y-477700D01*
X723700Y-477433D01*
X724300Y-476900D01*
G01X729200Y-474100D02*
X732400D01*
X732100Y-473167D01*
X731600Y-472633D01*
X730900Y-472367D01*
X730200Y-472500D01*
X729600Y-472900D01*
X729200Y-473833D01*
X729000Y-474634D01*
Y-475433D01*
X729200Y-476233D01*
X729700Y-477033D01*
X730300Y-477567D01*
X731000Y-477700D01*
X731700Y-477433D01*
X732400Y-476634D01*
G01X746700Y-469700D02*
Y-477700D01*
G01X745300Y-472367D02*
X748100D01*
G01X753300Y-477700D02*
Y-472367D01*
G01Y-473433D02*
X753800Y-472900D01*
X754300Y-472500D01*
X755000Y-472367D01*
X755500Y-472500D01*
X756100Y-472900D01*
G01X761200Y-474100D02*
X764400D01*
X764100Y-473167D01*
X763600Y-472633D01*
X762900Y-472367D01*
X762200Y-472500D01*
X761600Y-472900D01*
X761200Y-473833D01*
X761000Y-474634D01*
Y-475433D01*
X761200Y-476233D01*
X761700Y-477033D01*
X762300Y-477567D01*
X763000Y-477700D01*
X763700Y-477433D01*
X764400Y-476634D01*
G01X772500Y-477700D02*
Y-472367D01*
G01Y-473300D02*
X772100Y-472767D01*
X771500Y-472500D01*
X770800Y-472367D01*
X770100Y-472633D01*
X769500Y-473167D01*
X769100Y-473967D01*
X768900Y-475033D01*
X769100Y-476100D01*
X769500Y-476900D01*
X770100Y-477433D01*
X770800Y-477700D01*
X771500Y-477567D01*
X772100Y-477167D01*
X772500Y-476634D01*
G01X778700Y-469700D02*
Y-477700D01*
G01X777300Y-472367D02*
X780100D01*
G01X783700Y-477700D02*
Y-472367D01*
G01Y-473833D02*
X784000Y-473167D01*
X784500Y-472633D01*
X785200Y-472367D01*
X785900Y-472633D01*
X786400Y-473167D01*
X786700Y-473833D01*
Y-477700D01*
G01Y-473833D02*
X787000Y-473167D01*
X787500Y-472633D01*
X788200Y-472367D01*
X788900Y-472633D01*
X789400Y-473167D01*
X789700Y-473967D01*
Y-477700D01*
G01X793200Y-474100D02*
X796400D01*
X796100Y-473167D01*
X795600Y-472633D01*
X794900Y-472367D01*
X794200Y-472500D01*
X793600Y-472900D01*
X793200Y-473833D01*
X793000Y-474634D01*
Y-475433D01*
X793200Y-476233D01*
X793700Y-477033D01*
X794300Y-477567D01*
X795000Y-477700D01*
X795700Y-477433D01*
X796400Y-476634D01*
G01X801000Y-477700D02*
Y-472367D01*
G01Y-473700D02*
X801400Y-473033D01*
X802000Y-472500D01*
X802800Y-472367D01*
X803500Y-472500D01*
X804100Y-473033D01*
X804400Y-473967D01*
Y-477700D01*
G01X810700Y-469700D02*
Y-477700D01*
G01X809300Y-472367D02*
X812100D01*
G01X826700D02*
Y-477700D01*
G01Y-470233D02*
X826500Y-470100D01*
Y-469833D01*
X826700Y-469700D01*
X826900Y-469833D01*
Y-470100D01*
X826700Y-470233D01*
G01X833200Y-476767D02*
X833700Y-477300D01*
X834400Y-477700D01*
X835000D01*
X835600Y-477433D01*
X836000Y-477033D01*
X836200Y-476500D01*
X836100Y-475700D01*
X835700Y-475300D01*
X833900Y-474500D01*
X833500Y-473567D01*
X833700Y-472900D01*
X834100Y-472500D01*
X834700Y-472367D01*
X835300Y-472500D01*
X835900Y-472900D01*
G01X850700Y-472367D02*
Y-477700D01*
G01Y-470233D02*
X850500Y-470100D01*
Y-469833D01*
X850700Y-469700D01*
X850900Y-469833D01*
Y-470100D01*
X850700Y-470233D01*
G01X855700Y-477700D02*
Y-472367D01*
G01Y-473833D02*
X856000Y-473167D01*
X856500Y-472633D01*
X857200Y-472367D01*
X857900Y-472633D01*
X858400Y-473167D01*
X858700Y-473833D01*
Y-477700D01*
G01Y-473833D02*
X859000Y-473167D01*
X859500Y-472633D01*
X860200Y-472367D01*
X860900Y-472633D01*
X861400Y-473167D01*
X861700Y-473967D01*
Y-477700D01*
G01X863700D02*
Y-472367D01*
G01Y-473833D02*
X864000Y-473167D01*
X864500Y-472633D01*
X865200Y-472367D01*
X865900Y-472633D01*
X866400Y-473167D01*
X866700Y-473833D01*
Y-477700D01*
G01Y-473833D02*
X867000Y-473167D01*
X867500Y-472633D01*
X868200Y-472367D01*
X868900Y-472633D01*
X869400Y-473167D01*
X869700Y-473967D01*
Y-477700D01*
G01X873200Y-474100D02*
X876400D01*
X876100Y-473167D01*
X875600Y-472633D01*
X874900Y-472367D01*
X874200Y-472500D01*
X873600Y-472900D01*
X873200Y-473833D01*
X873000Y-474634D01*
Y-475433D01*
X873200Y-476233D01*
X873700Y-477033D01*
X874300Y-477567D01*
X875000Y-477700D01*
X875700Y-477433D01*
X876400Y-476634D01*
G01X881300Y-477700D02*
Y-472367D01*
G01Y-473433D02*
X881800Y-472900D01*
X882300Y-472500D01*
X883000Y-472367D01*
X883500Y-472500D01*
X884100Y-472900D01*
G01X889200Y-476767D02*
X889700Y-477300D01*
X890400Y-477700D01*
X891000D01*
X891600Y-477433D01*
X892000Y-477033D01*
X892200Y-476500D01*
X892100Y-475700D01*
X891700Y-475300D01*
X889900Y-474500D01*
X889500Y-473567D01*
X889700Y-472900D01*
X890100Y-472500D01*
X890700Y-472367D01*
X891300Y-472500D01*
X891900Y-472900D01*
G01X898700Y-472367D02*
Y-477700D01*
G01Y-470233D02*
X898500Y-470100D01*
Y-469833D01*
X898700Y-469700D01*
X898900Y-469833D01*
Y-470100D01*
X898700Y-470233D01*
G01X906700Y-477700D02*
X906100Y-477567D01*
X905500Y-477033D01*
X905100Y-476100D01*
X904900Y-475033D01*
X905100Y-473967D01*
X905500Y-473033D01*
X906100Y-472500D01*
X906700Y-472367D01*
X907300Y-472500D01*
X907900Y-473033D01*
X908300Y-473967D01*
X908400Y-475033D01*
X908300Y-476100D01*
X907900Y-477033D01*
X907300Y-477567D01*
X906700Y-477700D01*
G01X913000D02*
Y-472367D01*
G01Y-473700D02*
X913400Y-473033D01*
X914000Y-472500D01*
X914800Y-472367D01*
X915500Y-472500D01*
X916100Y-473033D01*
X916400Y-473967D01*
Y-477700D01*
G01X931300Y-473700D02*
X933300D01*
Y-476100D01*
X932700Y-476900D01*
X932000Y-477433D01*
X931000Y-477700D01*
X930000Y-477433D01*
X929300Y-476900D01*
X928700Y-476100D01*
X928300Y-475167D01*
X928100Y-474100D01*
Y-473167D01*
X928300Y-472367D01*
X928700Y-471433D01*
X929300Y-470633D01*
X929900Y-470100D01*
X930700Y-469700D01*
X931400D01*
X932200Y-469967D01*
X932800Y-470500D01*
G01X938700Y-477700D02*
X938100Y-477567D01*
X937500Y-477033D01*
X937100Y-476100D01*
X936900Y-475033D01*
X937100Y-473967D01*
X937500Y-473033D01*
X938100Y-472500D01*
X938700Y-472367D01*
X939300Y-472500D01*
X939900Y-473033D01*
X940300Y-473967D01*
X940400Y-475033D01*
X940300Y-476100D01*
X939900Y-477033D01*
X939300Y-477567D01*
X938700Y-477700D01*
G01X946700D02*
Y-469700D01*
G01X956500D02*
Y-477700D01*
G01Y-476500D02*
X956100Y-477167D01*
X955500Y-477567D01*
X954800Y-477700D01*
X954000Y-477433D01*
X953400Y-476767D01*
X953000Y-475967D01*
X952900Y-475033D01*
X953000Y-474100D01*
X953400Y-473300D01*
X954000Y-472633D01*
X954800Y-472367D01*
X955500Y-472500D01*
X956000Y-472767D01*
X956500Y-473300D01*
G01X962500Y-479167D02*
X962900Y-477433D01*
G01X972700Y-477700D02*
X968700D01*
Y-469700D01*
X972700D01*
G01X971100Y-473567D02*
X968700D01*
G01X977000Y-477700D02*
Y-472367D01*
G01Y-473700D02*
X977400Y-473033D01*
X978000Y-472500D01*
X978800Y-472367D01*
X979500Y-472500D01*
X980100Y-473033D01*
X980400Y-473967D01*
Y-477700D01*
G01X986700Y-469700D02*
Y-477700D01*
G01X985300Y-472367D02*
X988100D01*
G01X993200Y-474100D02*
X996400D01*
X996100Y-473167D01*
X995600Y-472633D01*
X994900Y-472367D01*
X994200Y-472500D01*
X993600Y-472900D01*
X993200Y-473833D01*
X993000Y-474634D01*
Y-475433D01*
X993200Y-476233D01*
X993700Y-477033D01*
X994300Y-477567D01*
X995000Y-477700D01*
X995700Y-477433D01*
X996400Y-476634D01*
G01X1001000Y-477700D02*
Y-469700D01*
G01X1004200Y-472367D02*
X1001000Y-475433D01*
G01X1002300Y-474233D02*
X1004400Y-477700D01*
G01X1018700D02*
X1018100Y-477567D01*
X1017500Y-477033D01*
X1017100Y-476100D01*
X1016900Y-475033D01*
X1017100Y-473967D01*
X1017500Y-473033D01*
X1018100Y-472500D01*
X1018700Y-472367D01*
X1019300Y-472500D01*
X1019900Y-473033D01*
X1020300Y-473967D01*
X1020400Y-475033D01*
X1020300Y-476100D01*
X1019900Y-477033D01*
X1019300Y-477567D01*
X1018700Y-477700D01*
G01X1025300D02*
Y-472367D01*
G01Y-473433D02*
X1025800Y-472900D01*
X1026300Y-472500D01*
X1027000Y-472367D01*
X1027500Y-472500D01*
X1028100Y-472900D01*
G01X1041500Y-469700D02*
X1043900D01*
G01X1042700D02*
Y-477700D01*
G01X1041500D02*
X1043900D01*
G01X1047700D02*
Y-472367D01*
G01Y-473833D02*
X1048000Y-473167D01*
X1048500Y-472633D01*
X1049200Y-472367D01*
X1049900Y-472633D01*
X1050400Y-473167D01*
X1050700Y-473833D01*
Y-477700D01*
G01Y-473833D02*
X1051000Y-473167D01*
X1051500Y-472633D01*
X1052200Y-472367D01*
X1052900Y-472633D01*
X1053400Y-473167D01*
X1053700Y-473967D01*
Y-477700D01*
G01X1056200D02*
X1058700Y-469700D01*
X1061200Y-477700D01*
G01X1060300Y-474900D02*
X1057100D01*
G01X1065300Y-479700D02*
X1066000Y-480233D01*
X1066800Y-480367D01*
X1067500Y-480233D01*
X1068100Y-479567D01*
X1068500Y-478633D01*
Y-472367D01*
G01Y-473433D02*
X1068100Y-472900D01*
X1067500Y-472500D01*
X1066800Y-472367D01*
X1066000Y-472633D01*
X1065500Y-473167D01*
X1065100Y-474100D01*
X1064900Y-475033D01*
X1065000Y-475833D01*
X1065400Y-476767D01*
X1066000Y-477433D01*
X1066800Y-477700D01*
X1067400Y-477567D01*
X1068100Y-477033D01*
X1068500Y-476500D01*
G01X1075200Y-480367D02*
X1076200Y-479033D01*
X1076700Y-477700D01*
Y-472367D01*
X1076200Y-471033D01*
X1075200Y-469700D01*
G01X674700Y-489700D02*
Y-481700D01*
X677100D01*
X677900Y-482100D01*
X678500Y-483033D01*
X678700Y-484100D01*
X678500Y-485167D01*
X678000Y-485967D01*
X677100Y-486367D01*
X674700D01*
G01X684700Y-481700D02*
Y-489700D01*
G01X682400Y-481700D02*
X687000D01*
G01X690600Y-489700D02*
Y-481700D01*
G01X694800D02*
Y-489700D01*
G01Y-485700D02*
X690600D01*
G01X707000Y-489700D02*
Y-481700D01*
G01Y-485567D02*
X707500Y-484900D01*
X708000Y-484500D01*
X708800Y-484367D01*
X709400Y-484500D01*
X710100Y-485033D01*
X710400Y-485833D01*
Y-489700D01*
G01X716700D02*
X716100Y-489567D01*
X715500Y-489033D01*
X715100Y-488100D01*
X714900Y-487033D01*
X715100Y-485967D01*
X715500Y-485033D01*
X716100Y-484500D01*
X716700Y-484367D01*
X717300Y-484500D01*
X717900Y-485033D01*
X718300Y-485967D01*
X718400Y-487033D01*
X718300Y-488100D01*
X717900Y-489033D01*
X717300Y-489567D01*
X716700Y-489700D01*
G01X724700D02*
Y-481700D01*
G01X731200Y-486100D02*
X734400D01*
X734100Y-485167D01*
X733600Y-484633D01*
X732900Y-484367D01*
X732200Y-484500D01*
X731600Y-484900D01*
X731200Y-485833D01*
X731000Y-486634D01*
Y-487433D01*
X731200Y-488233D01*
X731700Y-489033D01*
X732300Y-489567D01*
X733000Y-489700D01*
X733700Y-489433D01*
X734400Y-488634D01*
G01X748100Y-489700D02*
Y-482900D01*
X748300Y-482233D01*
X748700Y-481833D01*
X749300Y-481700D01*
X749900Y-481967D01*
X750200Y-482633D01*
G01X749000Y-484900D02*
X747000D01*
G01X756700Y-489700D02*
X756100Y-489567D01*
X755500Y-489033D01*
X755100Y-488100D01*
X754900Y-487033D01*
X755100Y-485967D01*
X755500Y-485033D01*
X756100Y-484500D01*
X756700Y-484367D01*
X757300Y-484500D01*
X757900Y-485033D01*
X758300Y-485967D01*
X758400Y-487033D01*
X758300Y-488100D01*
X757900Y-489033D01*
X757300Y-489567D01*
X756700Y-489700D01*
G01X763300D02*
Y-484367D01*
G01Y-485433D02*
X763800Y-484900D01*
X764300Y-484500D01*
X765000Y-484367D01*
X765500Y-484500D01*
X766100Y-484900D01*
G01X782300Y-485033D02*
X781600Y-484500D01*
X781000Y-484367D01*
X780200Y-484633D01*
X779600Y-485167D01*
X779200Y-486100D01*
X779100Y-487033D01*
X779200Y-487967D01*
X779600Y-488767D01*
X780200Y-489433D01*
X781000Y-489700D01*
X781700Y-489433D01*
X782300Y-488900D01*
G01X788700Y-489700D02*
X788100Y-489567D01*
X787500Y-489033D01*
X787100Y-488100D01*
X786900Y-487033D01*
X787100Y-485967D01*
X787500Y-485033D01*
X788100Y-484500D01*
X788700Y-484367D01*
X789300Y-484500D01*
X789900Y-485033D01*
X790300Y-485967D01*
X790400Y-487033D01*
X790300Y-488100D01*
X789900Y-489033D01*
X789300Y-489567D01*
X788700Y-489700D01*
G01X793700D02*
Y-484367D01*
G01Y-485833D02*
X794000Y-485167D01*
X794500Y-484633D01*
X795200Y-484367D01*
X795900Y-484633D01*
X796400Y-485167D01*
X796700Y-485833D01*
Y-489700D01*
G01Y-485833D02*
X797000Y-485167D01*
X797500Y-484633D01*
X798200Y-484367D01*
X798900Y-484633D01*
X799400Y-485167D01*
X799700Y-485967D01*
Y-489700D01*
G01X802900Y-492367D02*
Y-484367D01*
G01Y-485567D02*
X803400Y-484900D01*
X803900Y-484500D01*
X804700Y-484367D01*
X805400Y-484500D01*
X806100Y-485167D01*
X806400Y-486100D01*
X806500Y-487033D01*
X806400Y-487967D01*
X806100Y-488900D01*
X805500Y-489433D01*
X804700Y-489700D01*
X804000Y-489567D01*
X803300Y-489167D01*
X802900Y-488634D01*
G01X812700Y-489700D02*
X812100Y-489567D01*
X811500Y-489033D01*
X811100Y-488100D01*
X810900Y-487033D01*
X811100Y-485967D01*
X811500Y-485033D01*
X812100Y-484500D01*
X812700Y-484367D01*
X813300Y-484500D01*
X813900Y-485033D01*
X814300Y-485967D01*
X814400Y-487033D01*
X814300Y-488100D01*
X813900Y-489033D01*
X813300Y-489567D01*
X812700Y-489700D01*
G01X819000D02*
Y-484367D01*
G01Y-485700D02*
X819400Y-485033D01*
X820000Y-484500D01*
X820800Y-484367D01*
X821500Y-484500D01*
X822100Y-485033D01*
X822400Y-485967D01*
Y-489700D01*
G01X827200Y-486100D02*
X830400D01*
X830100Y-485167D01*
X829600Y-484633D01*
X828900Y-484367D01*
X828200Y-484500D01*
X827600Y-484900D01*
X827200Y-485833D01*
X827000Y-486634D01*
Y-487433D01*
X827200Y-488233D01*
X827700Y-489033D01*
X828300Y-489567D01*
X829000Y-489700D01*
X829700Y-489433D01*
X830400Y-488634D01*
G01X835000Y-489700D02*
Y-484367D01*
G01Y-485700D02*
X835400Y-485033D01*
X836000Y-484500D01*
X836800Y-484367D01*
X837500Y-484500D01*
X838100Y-485033D01*
X838400Y-485967D01*
Y-489700D01*
G01X844700Y-481700D02*
Y-489700D01*
G01X843300Y-484367D02*
X846100D01*
G01X860200Y-492367D02*
X859200Y-491033D01*
X858700Y-489700D01*
Y-484367D01*
X859200Y-483033D01*
X860200Y-481700D01*
G01X868700Y-489700D02*
Y-481700D01*
X867500Y-483300D01*
G01Y-489700D02*
X869900D01*
G01X874800Y-486367D02*
X875500Y-485433D01*
X876100Y-484900D01*
X876900Y-484633D01*
X877600Y-484900D01*
X878100Y-485433D01*
X878500Y-486233D01*
X878600Y-487167D01*
X878500Y-487967D01*
X878100Y-488767D01*
X877500Y-489433D01*
X876800Y-489700D01*
X876000Y-489433D01*
X875300Y-488634D01*
X874900Y-487433D01*
X874800Y-486100D01*
X875000Y-484367D01*
X875300Y-483433D01*
X875800Y-482500D01*
X876500Y-481833D01*
X877200Y-481700D01*
X877900Y-481967D01*
X878400Y-482633D01*
G01X881700Y-489700D02*
Y-484367D01*
G01Y-485833D02*
X882000Y-485167D01*
X882500Y-484633D01*
X883200Y-484367D01*
X883900Y-484633D01*
X884400Y-485167D01*
X884700Y-485833D01*
Y-489700D01*
G01Y-485833D02*
X885000Y-485167D01*
X885500Y-484633D01*
X886200Y-484367D01*
X886900Y-484633D01*
X887400Y-485167D01*
X887700Y-485967D01*
Y-489700D01*
G01X892700Y-484367D02*
Y-489700D01*
G01Y-482233D02*
X892500Y-482100D01*
Y-481833D01*
X892700Y-481700D01*
X892900Y-481833D01*
Y-482100D01*
X892700Y-482233D01*
G01X900700Y-489700D02*
Y-481700D01*
G01X918700Y-489700D02*
X914700Y-487033D01*
X918700Y-484367D01*
G01X931200Y-488767D02*
X931700Y-489300D01*
X932400Y-489700D01*
X933000D01*
X933600Y-489433D01*
X934000Y-489033D01*
X934200Y-488500D01*
X934100Y-487700D01*
X933700Y-487300D01*
X931900Y-486500D01*
X931500Y-485567D01*
X931700Y-484900D01*
X932100Y-484500D01*
X932700Y-484367D01*
X933300Y-484500D01*
X933900Y-484900D01*
G01X940700Y-484367D02*
Y-489700D01*
G01Y-482233D02*
X940500Y-482100D01*
Y-481833D01*
X940700Y-481700D01*
X940900Y-481833D01*
Y-482100D01*
X940700Y-482233D01*
G01X947200Y-484367D02*
X950200D01*
X947200Y-489700D01*
X950200D01*
G01X955200Y-486100D02*
X958400D01*
X958100Y-485167D01*
X957600Y-484633D01*
X956900Y-484367D01*
X956200Y-484500D01*
X955600Y-484900D01*
X955200Y-485833D01*
X955000Y-486634D01*
Y-487433D01*
X955200Y-488233D01*
X955700Y-489033D01*
X956300Y-489567D01*
X957000Y-489700D01*
X957700Y-489433D01*
X958400Y-488634D01*
G01X974700Y-489700D02*
X970700Y-487033D01*
X974700Y-484367D01*
G01X980700Y-489700D02*
Y-481700D01*
X979500Y-483300D01*
G01Y-489700D02*
X981900D01*
G01X987000Y-488767D02*
X987700Y-489433D01*
X988500Y-489700D01*
X989300Y-489433D01*
X990000Y-488634D01*
X990500Y-487433D01*
X990700Y-486233D01*
Y-484767D01*
X990500Y-483567D01*
X990000Y-482500D01*
X989400Y-481967D01*
X988700Y-481700D01*
X987900Y-481967D01*
X987300Y-482500D01*
X986900Y-483300D01*
X986700Y-484367D01*
X986900Y-485300D01*
X987400Y-486233D01*
X988000Y-486767D01*
X988700Y-486900D01*
X989500Y-486634D01*
X990100Y-485967D01*
X990700Y-484767D01*
G01X996500Y-489700D02*
X996700Y-487967D01*
X997000Y-486500D01*
X997400Y-485167D01*
X997900Y-483700D01*
X998700Y-481700D01*
X994700D01*
G01X1001700Y-489700D02*
Y-484367D01*
G01Y-485833D02*
X1002000Y-485167D01*
X1002500Y-484633D01*
X1003200Y-484367D01*
X1003900Y-484633D01*
X1004400Y-485167D01*
X1004700Y-485833D01*
Y-489700D01*
G01Y-485833D02*
X1005000Y-485167D01*
X1005500Y-484633D01*
X1006200Y-484367D01*
X1006900Y-484633D01*
X1007400Y-485167D01*
X1007700Y-485967D01*
Y-489700D01*
G01X1012700Y-484367D02*
Y-489700D01*
G01Y-482233D02*
X1012500Y-482100D01*
Y-481833D01*
X1012700Y-481700D01*
X1012900Y-481833D01*
Y-482100D01*
X1012700Y-482233D01*
G01X1020700Y-489700D02*
Y-481700D01*
G01X1029200Y-492367D02*
X1030200Y-491033D01*
X1030700Y-489700D01*
Y-484367D01*
X1030200Y-483033D01*
X1029200Y-481700D01*
G01X674200Y-464700D02*
Y-456700D01*
X676600D01*
X677400Y-457100D01*
X678000Y-458033D01*
X678200Y-459100D01*
X678000Y-460167D01*
X677500Y-460967D01*
X676600Y-461367D01*
X674200D01*
G01X684200Y-456700D02*
Y-464700D01*
G01X681900Y-456700D02*
X686500D01*
G01X690100Y-464700D02*
Y-456700D01*
G01X694300D02*
Y-464700D01*
G01Y-460700D02*
X690100D01*
G01X706500Y-464700D02*
Y-456700D01*
G01Y-460567D02*
X707000Y-459900D01*
X707500Y-459500D01*
X708300Y-459367D01*
X708900Y-459500D01*
X709600Y-460033D01*
X709900Y-460833D01*
Y-464700D01*
G01X716200D02*
X715600Y-464567D01*
X715000Y-464033D01*
X714600Y-463100D01*
X714400Y-462033D01*
X714600Y-460967D01*
X715000Y-460033D01*
X715600Y-459500D01*
X716200Y-459367D01*
X716800Y-459500D01*
X717400Y-460033D01*
X717800Y-460967D01*
X717900Y-462033D01*
X717800Y-463100D01*
X717400Y-464033D01*
X716800Y-464567D01*
X716200Y-464700D01*
G01X724200D02*
Y-456700D01*
G01X730700Y-461100D02*
X733900D01*
X733600Y-460167D01*
X733100Y-459633D01*
X732400Y-459367D01*
X731700Y-459500D01*
X731100Y-459900D01*
X730700Y-460833D01*
X730500Y-461634D01*
Y-462433D01*
X730700Y-463233D01*
X731200Y-464033D01*
X731800Y-464567D01*
X732500Y-464700D01*
X733200Y-464433D01*
X733900Y-463634D01*
G01X747600Y-464700D02*
Y-457900D01*
X747800Y-457233D01*
X748200Y-456833D01*
X748800Y-456700D01*
X749400Y-456967D01*
X749700Y-457633D01*
G01X748500Y-459900D02*
X746500D01*
G01X756200Y-464700D02*
X755600Y-464567D01*
X755000Y-464033D01*
X754600Y-463100D01*
X754400Y-462033D01*
X754600Y-460967D01*
X755000Y-460033D01*
X755600Y-459500D01*
X756200Y-459367D01*
X756800Y-459500D01*
X757400Y-460033D01*
X757800Y-460967D01*
X757900Y-462033D01*
X757800Y-463100D01*
X757400Y-464033D01*
X756800Y-464567D01*
X756200Y-464700D01*
G01X762800D02*
Y-459367D01*
G01Y-460433D02*
X763300Y-459900D01*
X763800Y-459500D01*
X764500Y-459367D01*
X765000Y-459500D01*
X765600Y-459900D01*
G01X781800Y-460033D02*
X781100Y-459500D01*
X780500Y-459367D01*
X779700Y-459633D01*
X779100Y-460167D01*
X778700Y-461100D01*
X778600Y-462033D01*
X778700Y-462967D01*
X779100Y-463767D01*
X779700Y-464433D01*
X780500Y-464700D01*
X781200Y-464433D01*
X781800Y-463900D01*
G01X788200Y-464700D02*
X787600Y-464567D01*
X787000Y-464033D01*
X786600Y-463100D01*
X786400Y-462033D01*
X786600Y-460967D01*
X787000Y-460033D01*
X787600Y-459500D01*
X788200Y-459367D01*
X788800Y-459500D01*
X789400Y-460033D01*
X789800Y-460967D01*
X789900Y-462033D01*
X789800Y-463100D01*
X789400Y-464033D01*
X788800Y-464567D01*
X788200Y-464700D01*
G01X793200D02*
Y-459367D01*
G01Y-460833D02*
X793500Y-460167D01*
X794000Y-459633D01*
X794700Y-459367D01*
X795400Y-459633D01*
X795900Y-460167D01*
X796200Y-460833D01*
Y-464700D01*
G01Y-460833D02*
X796500Y-460167D01*
X797000Y-459633D01*
X797700Y-459367D01*
X798400Y-459633D01*
X798900Y-460167D01*
X799200Y-460967D01*
Y-464700D01*
G01X802400Y-467367D02*
Y-459367D01*
G01Y-460567D02*
X802900Y-459900D01*
X803400Y-459500D01*
X804200Y-459367D01*
X804900Y-459500D01*
X805600Y-460167D01*
X805900Y-461100D01*
X806000Y-462033D01*
X805900Y-462967D01*
X805600Y-463900D01*
X805000Y-464433D01*
X804200Y-464700D01*
X803500Y-464567D01*
X802800Y-464167D01*
X802400Y-463634D01*
G01X812200Y-464700D02*
X811600Y-464567D01*
X811000Y-464033D01*
X810600Y-463100D01*
X810400Y-462033D01*
X810600Y-460967D01*
X811000Y-460033D01*
X811600Y-459500D01*
X812200Y-459367D01*
X812800Y-459500D01*
X813400Y-460033D01*
X813800Y-460967D01*
X813900Y-462033D01*
X813800Y-463100D01*
X813400Y-464033D01*
X812800Y-464567D01*
X812200Y-464700D01*
G01X818500D02*
Y-459367D01*
G01Y-460700D02*
X818900Y-460033D01*
X819500Y-459500D01*
X820300Y-459367D01*
X821000Y-459500D01*
X821600Y-460033D01*
X821900Y-460967D01*
Y-464700D01*
G01X826700Y-461100D02*
X829900D01*
X829600Y-460167D01*
X829100Y-459633D01*
X828400Y-459367D01*
X827700Y-459500D01*
X827100Y-459900D01*
X826700Y-460833D01*
X826500Y-461634D01*
Y-462433D01*
X826700Y-463233D01*
X827200Y-464033D01*
X827800Y-464567D01*
X828500Y-464700D01*
X829200Y-464433D01*
X829900Y-463634D01*
G01X834500Y-464700D02*
Y-459367D01*
G01Y-460700D02*
X834900Y-460033D01*
X835500Y-459500D01*
X836300Y-459367D01*
X837000Y-459500D01*
X837600Y-460033D01*
X837900Y-460967D01*
Y-464700D01*
G01X844200Y-456700D02*
Y-464700D01*
G01X842800Y-459367D02*
X845600D01*
G01X859700Y-467367D02*
X858700Y-466033D01*
X858200Y-464700D01*
Y-459367D01*
X858700Y-458033D01*
X859700Y-456700D01*
G01X868200Y-464700D02*
Y-456700D01*
X867000Y-458300D01*
G01Y-464700D02*
X869400D01*
G01X874300Y-461367D02*
X875000Y-460433D01*
X875600Y-459900D01*
X876400Y-459633D01*
X877100Y-459900D01*
X877600Y-460433D01*
X878000Y-461233D01*
X878100Y-462167D01*
X878000Y-462967D01*
X877600Y-463767D01*
X877000Y-464433D01*
X876300Y-464700D01*
X875500Y-464433D01*
X874800Y-463634D01*
X874400Y-462433D01*
X874300Y-461100D01*
X874500Y-459367D01*
X874800Y-458433D01*
X875300Y-457500D01*
X876000Y-456833D01*
X876700Y-456700D01*
X877400Y-456967D01*
X877900Y-457633D01*
G01X881200Y-464700D02*
Y-459367D01*
G01Y-460833D02*
X881500Y-460167D01*
X882000Y-459633D01*
X882700Y-459367D01*
X883400Y-459633D01*
X883900Y-460167D01*
X884200Y-460833D01*
Y-464700D01*
G01Y-460833D02*
X884500Y-460167D01*
X885000Y-459633D01*
X885700Y-459367D01*
X886400Y-459633D01*
X886900Y-460167D01*
X887200Y-460967D01*
Y-464700D01*
G01X892200Y-459367D02*
Y-464700D01*
G01Y-457233D02*
X892000Y-457100D01*
Y-456833D01*
X892200Y-456700D01*
X892400Y-456833D01*
Y-457100D01*
X892200Y-457233D01*
G01X900200Y-464700D02*
Y-456700D01*
G01X918200Y-464700D02*
X914200Y-462033D01*
X918200Y-459367D01*
G01X930700Y-463767D02*
X931200Y-464300D01*
X931900Y-464700D01*
X932500D01*
X933100Y-464433D01*
X933500Y-464033D01*
X933700Y-463500D01*
X933600Y-462700D01*
X933200Y-462300D01*
X931400Y-461500D01*
X931000Y-460567D01*
X931200Y-459900D01*
X931600Y-459500D01*
X932200Y-459367D01*
X932800Y-459500D01*
X933400Y-459900D01*
G01X940200Y-459367D02*
Y-464700D01*
G01Y-457233D02*
X940000Y-457100D01*
Y-456833D01*
X940200Y-456700D01*
X940400Y-456833D01*
Y-457100D01*
X940200Y-457233D01*
G01X946700Y-459367D02*
X949700D01*
X946700Y-464700D01*
X949700D01*
G01X954700Y-461100D02*
X957900D01*
X957600Y-460167D01*
X957100Y-459633D01*
X956400Y-459367D01*
X955700Y-459500D01*
X955100Y-459900D01*
X954700Y-460833D01*
X954500Y-461634D01*
Y-462433D01*
X954700Y-463233D01*
X955200Y-464033D01*
X955800Y-464567D01*
X956500Y-464700D01*
X957200Y-464433D01*
X957900Y-463634D01*
G01X974200Y-464700D02*
X970200Y-462033D01*
X974200Y-459367D01*
G01X980200Y-464700D02*
Y-456700D01*
X979000Y-458300D01*
G01Y-464700D02*
X981400D01*
G01X986500Y-463767D02*
X987200Y-464433D01*
X988000Y-464700D01*
X988800Y-464433D01*
X989500Y-463634D01*
X990000Y-462433D01*
X990200Y-461233D01*
Y-459767D01*
X990000Y-458567D01*
X989500Y-457500D01*
X988900Y-456967D01*
X988200Y-456700D01*
X987400Y-456967D01*
X986800Y-457500D01*
X986400Y-458300D01*
X986200Y-459367D01*
X986400Y-460300D01*
X986900Y-461233D01*
X987500Y-461767D01*
X988200Y-461900D01*
X989000Y-461634D01*
X989600Y-460967D01*
X990200Y-459767D01*
G01X996000Y-464700D02*
X996200Y-462967D01*
X996500Y-461500D01*
X996900Y-460167D01*
X997400Y-458700D01*
X998200Y-456700D01*
X994200D01*
G01X1001200Y-464700D02*
Y-459367D01*
G01Y-460833D02*
X1001500Y-460167D01*
X1002000Y-459633D01*
X1002700Y-459367D01*
X1003400Y-459633D01*
X1003900Y-460167D01*
X1004200Y-460833D01*
Y-464700D01*
G01Y-460833D02*
X1004500Y-460167D01*
X1005000Y-459633D01*
X1005700Y-459367D01*
X1006400Y-459633D01*
X1006900Y-460167D01*
X1007200Y-460967D01*
Y-464700D01*
G01X1012200Y-459367D02*
Y-464700D01*
G01Y-457233D02*
X1012000Y-457100D01*
Y-456833D01*
X1012200Y-456700D01*
X1012400Y-456833D01*
Y-457100D01*
X1012200Y-457233D01*
G01X1020200Y-464700D02*
Y-456700D01*
G01X1028700Y-467367D02*
X1029700Y-466033D01*
X1030200Y-464700D01*
Y-459367D01*
X1029700Y-458033D01*
X1028700Y-456700D01*
G01X673700Y-444200D02*
Y-452200D01*
X677700D01*
G01X685500D02*
Y-446867D01*
G01Y-447800D02*
X685100Y-447267D01*
X684500Y-447000D01*
X683800Y-446867D01*
X683100Y-447133D01*
X682500Y-447667D01*
X682100Y-448467D01*
X681900Y-449533D01*
X682100Y-450600D01*
X682500Y-451400D01*
X683100Y-451933D01*
X683800Y-452200D01*
X684500Y-452067D01*
X685100Y-451667D01*
X685500Y-451134D01*
G01X690200Y-451267D02*
X690700Y-451800D01*
X691400Y-452200D01*
X692000D01*
X692600Y-451933D01*
X693000Y-451533D01*
X693200Y-451000D01*
X693100Y-450200D01*
X692700Y-449800D01*
X690900Y-449000D01*
X690500Y-448067D01*
X690700Y-447400D01*
X691100Y-447000D01*
X691700Y-446867D01*
X692300Y-447000D01*
X692900Y-447400D01*
G01X698200Y-448600D02*
X701400D01*
X701100Y-447667D01*
X700600Y-447133D01*
X699900Y-446867D01*
X699200Y-447000D01*
X698600Y-447400D01*
X698200Y-448333D01*
X698000Y-449134D01*
Y-449933D01*
X698200Y-450733D01*
X698700Y-451533D01*
X699300Y-452067D01*
X700000Y-452200D01*
X700700Y-451933D01*
X701400Y-451134D01*
G01X706300Y-452200D02*
Y-446867D01*
G01Y-447933D02*
X706800Y-447400D01*
X707300Y-447000D01*
X708000Y-446867D01*
X708500Y-447000D01*
X709100Y-447400D01*
G01X721900Y-446867D02*
X723700Y-452200D01*
X725500Y-446867D01*
G01X731700D02*
Y-452200D01*
G01Y-444733D02*
X731500Y-444600D01*
Y-444333D01*
X731700Y-444200D01*
X731900Y-444333D01*
Y-444600D01*
X731700Y-444733D01*
G01X741500Y-452200D02*
Y-446867D01*
G01Y-447800D02*
X741100Y-447267D01*
X740500Y-447000D01*
X739800Y-446867D01*
X739100Y-447133D01*
X738500Y-447667D01*
X738100Y-448467D01*
X737900Y-449533D01*
X738100Y-450600D01*
X738500Y-451400D01*
X739100Y-451933D01*
X739800Y-452200D01*
X740500Y-452067D01*
X741100Y-451667D01*
X741500Y-451134D01*
G01X754000Y-452200D02*
Y-444200D01*
G01Y-448067D02*
X754500Y-447400D01*
X755000Y-447000D01*
X755800Y-446867D01*
X756400Y-447000D01*
X757100Y-447533D01*
X757400Y-448333D01*
Y-452200D01*
G01X763700D02*
X763100Y-452067D01*
X762500Y-451533D01*
X762100Y-450600D01*
X761900Y-449533D01*
X762100Y-448467D01*
X762500Y-447533D01*
X763100Y-447000D01*
X763700Y-446867D01*
X764300Y-447000D01*
X764900Y-447533D01*
X765300Y-448467D01*
X765400Y-449533D01*
X765300Y-450600D01*
X764900Y-451533D01*
X764300Y-452067D01*
X763700Y-452200D01*
G01X771700D02*
Y-444200D01*
G01X778200Y-448600D02*
X781400D01*
X781100Y-447667D01*
X780600Y-447133D01*
X779900Y-446867D01*
X779200Y-447000D01*
X778600Y-447400D01*
X778200Y-448333D01*
X778000Y-449134D01*
Y-449933D01*
X778200Y-450733D01*
X778700Y-451533D01*
X779300Y-452067D01*
X780000Y-452200D01*
X780700Y-451933D01*
X781400Y-451134D01*
G01X795200Y-454867D02*
X794200Y-453533D01*
X793700Y-452200D01*
Y-446867D01*
X794200Y-445533D01*
X795200Y-444200D01*
G01X801900Y-452200D02*
Y-444200D01*
G01Y-448200D02*
X802400Y-447400D01*
X803000Y-447000D01*
X803600Y-446867D01*
X804500Y-447133D01*
X805100Y-447667D01*
X805500Y-448600D01*
Y-449667D01*
X805300Y-450733D01*
X804900Y-451533D01*
X804200Y-452067D01*
X803600Y-452200D01*
X803000Y-452067D01*
X802400Y-451667D01*
X801900Y-451000D01*
G01X810200Y-448600D02*
X813400D01*
X813100Y-447667D01*
X812600Y-447133D01*
X811900Y-446867D01*
X811200Y-447000D01*
X810600Y-447400D01*
X810200Y-448333D01*
X810000Y-449134D01*
Y-449933D01*
X810200Y-450733D01*
X810700Y-451533D01*
X811300Y-452067D01*
X812000Y-452200D01*
X812700Y-451933D01*
X813400Y-451134D01*
G01X819100Y-452200D02*
Y-445400D01*
X819300Y-444733D01*
X819700Y-444333D01*
X820300Y-444200D01*
X820900Y-444467D01*
X821200Y-445133D01*
G01X820000Y-447400D02*
X818000D01*
G01X827700Y-452200D02*
X827100Y-452067D01*
X826500Y-451533D01*
X826100Y-450600D01*
X825900Y-449533D01*
X826100Y-448467D01*
X826500Y-447533D01*
X827100Y-447000D01*
X827700Y-446867D01*
X828300Y-447000D01*
X828900Y-447533D01*
X829300Y-448467D01*
X829400Y-449533D01*
X829300Y-450600D01*
X828900Y-451533D01*
X828300Y-452067D01*
X827700Y-452200D01*
G01X834300D02*
Y-446867D01*
G01Y-447933D02*
X834800Y-447400D01*
X835300Y-447000D01*
X836000Y-446867D01*
X836500Y-447000D01*
X837100Y-447400D01*
G01X842200Y-448600D02*
X845400D01*
X845100Y-447667D01*
X844600Y-447133D01*
X843900Y-446867D01*
X843200Y-447000D01*
X842600Y-447400D01*
X842200Y-448333D01*
X842000Y-449134D01*
Y-449933D01*
X842200Y-450733D01*
X842700Y-451533D01*
X843300Y-452067D01*
X844000Y-452200D01*
X844700Y-451933D01*
X845400Y-451134D01*
G01X859700Y-444200D02*
Y-452200D01*
G01X858300Y-446867D02*
X861100D01*
G01X866000Y-452200D02*
Y-444200D01*
G01Y-448067D02*
X866500Y-447400D01*
X867000Y-447000D01*
X867800Y-446867D01*
X868400Y-447000D01*
X869100Y-447533D01*
X869400Y-448333D01*
Y-452200D01*
G01X874200Y-448600D02*
X877400D01*
X877100Y-447667D01*
X876600Y-447133D01*
X875900Y-446867D01*
X875200Y-447000D01*
X874600Y-447400D01*
X874200Y-448333D01*
X874000Y-449134D01*
Y-449933D01*
X874200Y-450733D01*
X874700Y-451533D01*
X875300Y-452067D01*
X876000Y-452200D01*
X876700Y-451933D01*
X877400Y-451134D01*
G01X893300Y-447533D02*
X892600Y-447000D01*
X892000Y-446867D01*
X891200Y-447133D01*
X890600Y-447667D01*
X890200Y-448600D01*
X890100Y-449533D01*
X890200Y-450467D01*
X890600Y-451267D01*
X891200Y-451933D01*
X892000Y-452200D01*
X892700Y-451933D01*
X893300Y-451400D01*
G01X899700Y-452200D02*
X899100Y-452067D01*
X898500Y-451533D01*
X898100Y-450600D01*
X897900Y-449533D01*
X898100Y-448467D01*
X898500Y-447533D01*
X899100Y-447000D01*
X899700Y-446867D01*
X900300Y-447000D01*
X900900Y-447533D01*
X901300Y-448467D01*
X901400Y-449533D01*
X901300Y-450600D01*
X900900Y-451533D01*
X900300Y-452067D01*
X899700Y-452200D01*
G01X905900Y-454867D02*
Y-446867D01*
G01Y-448067D02*
X906400Y-447400D01*
X906900Y-447000D01*
X907700Y-446867D01*
X908400Y-447000D01*
X909100Y-447667D01*
X909400Y-448600D01*
X909500Y-449533D01*
X909400Y-450467D01*
X909100Y-451400D01*
X908500Y-451933D01*
X907700Y-452200D01*
X907000Y-452067D01*
X906300Y-451667D01*
X905900Y-451134D01*
G01X913900Y-454867D02*
Y-446867D01*
G01Y-448067D02*
X914400Y-447400D01*
X914900Y-447000D01*
X915700Y-446867D01*
X916400Y-447000D01*
X917100Y-447667D01*
X917400Y-448600D01*
X917500Y-449533D01*
X917400Y-450467D01*
X917100Y-451400D01*
X916500Y-451933D01*
X915700Y-452200D01*
X915000Y-452067D01*
X914300Y-451667D01*
X913900Y-451134D01*
G01X922200Y-448600D02*
X925400D01*
X925100Y-447667D01*
X924600Y-447133D01*
X923900Y-446867D01*
X923200Y-447000D01*
X922600Y-447400D01*
X922200Y-448333D01*
X922000Y-449134D01*
Y-449933D01*
X922200Y-450733D01*
X922700Y-451533D01*
X923300Y-452067D01*
X924000Y-452200D01*
X924700Y-451933D01*
X925400Y-451134D01*
G01X930300Y-452200D02*
Y-446867D01*
G01Y-447933D02*
X930800Y-447400D01*
X931300Y-447000D01*
X932000Y-446867D01*
X932500Y-447000D01*
X933100Y-447400D01*
G01X945900Y-454867D02*
Y-446867D01*
G01Y-448067D02*
X946400Y-447400D01*
X946900Y-447000D01*
X947700Y-446867D01*
X948400Y-447000D01*
X949100Y-447667D01*
X949400Y-448600D01*
X949500Y-449533D01*
X949400Y-450467D01*
X949100Y-451400D01*
X948500Y-451933D01*
X947700Y-452200D01*
X947000Y-452067D01*
X946300Y-451667D01*
X945900Y-451134D01*
G01X955700Y-452200D02*
Y-444200D01*
G01X965500Y-452200D02*
Y-446867D01*
G01Y-447800D02*
X965100Y-447267D01*
X964500Y-447000D01*
X963800Y-446867D01*
X963100Y-447133D01*
X962500Y-447667D01*
X962100Y-448467D01*
X961900Y-449533D01*
X962100Y-450600D01*
X962500Y-451400D01*
X963100Y-451933D01*
X963800Y-452200D01*
X964500Y-452067D01*
X965100Y-451667D01*
X965500Y-451134D01*
G01X971700Y-444200D02*
Y-452200D01*
G01X970300Y-446867D02*
X973100D01*
G01X979700D02*
Y-452200D01*
G01Y-444733D02*
X979500Y-444600D01*
Y-444333D01*
X979700Y-444200D01*
X979900Y-444333D01*
Y-444600D01*
X979700Y-444733D01*
G01X986000Y-452200D02*
Y-446867D01*
G01Y-448200D02*
X986400Y-447533D01*
X987000Y-447000D01*
X987800Y-446867D01*
X988500Y-447000D01*
X989100Y-447533D01*
X989400Y-448467D01*
Y-452200D01*
G01X994300Y-454200D02*
X995000Y-454733D01*
X995800Y-454867D01*
X996500Y-454733D01*
X997100Y-454067D01*
X997500Y-453133D01*
Y-446867D01*
G01Y-447933D02*
X997100Y-447400D01*
X996500Y-447000D01*
X995800Y-446867D01*
X995000Y-447133D01*
X994500Y-447667D01*
X994100Y-448600D01*
X993900Y-449533D01*
X994000Y-450333D01*
X994400Y-451267D01*
X995000Y-451933D01*
X995800Y-452200D01*
X996400Y-452067D01*
X997100Y-451533D01*
X997500Y-451000D01*
G01X1004200Y-454867D02*
X1005200Y-453533D01*
X1005700Y-452200D01*
Y-446867D01*
X1005200Y-445533D01*
X1004200Y-444200D01*
G01X673200Y-431700D02*
X675700Y-439700D01*
X678200Y-431700D01*
G01X683700Y-434367D02*
Y-439700D01*
G01Y-432233D02*
X683500Y-432100D01*
Y-431833D01*
X683700Y-431700D01*
X683900Y-431833D01*
Y-432100D01*
X683700Y-432233D01*
G01X693500Y-439700D02*
Y-434367D01*
G01Y-435300D02*
X693100Y-434767D01*
X692500Y-434500D01*
X691800Y-434367D01*
X691100Y-434633D01*
X690500Y-435167D01*
X690100Y-435967D01*
X689900Y-437033D01*
X690100Y-438100D01*
X690500Y-438900D01*
X691100Y-439433D01*
X691800Y-439700D01*
X692500Y-439567D01*
X693100Y-439167D01*
X693500Y-438634D01*
G01X705600Y-439700D02*
Y-431700D01*
G01X709800D02*
Y-439700D01*
G01Y-435700D02*
X705600D01*
G01X715700Y-439700D02*
X715100Y-439567D01*
X714500Y-439033D01*
X714100Y-438100D01*
X713900Y-437033D01*
X714100Y-435967D01*
X714500Y-435033D01*
X715100Y-434500D01*
X715700Y-434367D01*
X716300Y-434500D01*
X716900Y-435033D01*
X717300Y-435967D01*
X717400Y-437033D01*
X717300Y-438100D01*
X716900Y-439033D01*
X716300Y-439567D01*
X715700Y-439700D01*
G01X723700D02*
Y-431700D01*
G01X730200Y-436100D02*
X733400D01*
X733100Y-435167D01*
X732600Y-434633D01*
X731900Y-434367D01*
X731200Y-434500D01*
X730600Y-434900D01*
X730200Y-435833D01*
X730000Y-436634D01*
Y-437433D01*
X730200Y-438233D01*
X730700Y-439033D01*
X731300Y-439567D01*
X732000Y-439700D01*
X732700Y-439433D01*
X733400Y-438634D01*
G01X747200Y-442367D02*
X746200Y-441033D01*
X745700Y-439700D01*
Y-434367D01*
X746200Y-433033D01*
X747200Y-431700D01*
G01X754000Y-439700D02*
Y-431700D01*
G01Y-435567D02*
X754500Y-434900D01*
X755000Y-434500D01*
X755800Y-434367D01*
X756400Y-434500D01*
X757100Y-435033D01*
X757400Y-435833D01*
Y-439700D01*
G01X763700D02*
X763100Y-439567D01*
X762500Y-439033D01*
X762100Y-438100D01*
X761900Y-437033D01*
X762100Y-435967D01*
X762500Y-435033D01*
X763100Y-434500D01*
X763700Y-434367D01*
X764300Y-434500D01*
X764900Y-435033D01*
X765300Y-435967D01*
X765400Y-437033D01*
X765300Y-438100D01*
X764900Y-439033D01*
X764300Y-439567D01*
X763700Y-439700D01*
G01X771700D02*
Y-431700D01*
G01X778200Y-436100D02*
X781400D01*
X781100Y-435167D01*
X780600Y-434633D01*
X779900Y-434367D01*
X779200Y-434500D01*
X778600Y-434900D01*
X778200Y-435833D01*
X778000Y-436634D01*
Y-437433D01*
X778200Y-438233D01*
X778700Y-439033D01*
X779300Y-439567D01*
X780000Y-439700D01*
X780700Y-439433D01*
X781400Y-438634D01*
G01X794200Y-438767D02*
X794700Y-439300D01*
X795400Y-439700D01*
X796000D01*
X796600Y-439433D01*
X797000Y-439033D01*
X797200Y-438500D01*
X797100Y-437700D01*
X796700Y-437300D01*
X794900Y-436500D01*
X794500Y-435567D01*
X794700Y-434900D01*
X795100Y-434500D01*
X795700Y-434367D01*
X796300Y-434500D01*
X796900Y-434900D01*
G01X803700Y-434367D02*
Y-439700D01*
G01Y-432233D02*
X803500Y-432100D01*
Y-431833D01*
X803700Y-431700D01*
X803900Y-431833D01*
Y-432100D01*
X803700Y-432233D01*
G01X810200Y-434367D02*
X813200D01*
X810200Y-439700D01*
X813200D01*
G01X818200Y-436100D02*
X821400D01*
X821100Y-435167D01*
X820600Y-434633D01*
X819900Y-434367D01*
X819200Y-434500D01*
X818600Y-434900D01*
X818200Y-435833D01*
X818000Y-436634D01*
Y-437433D01*
X818200Y-438233D01*
X818700Y-439033D01*
X819300Y-439567D01*
X820000Y-439700D01*
X820700Y-439433D01*
X821400Y-438634D01*
G01X837700Y-439700D02*
X833700Y-437033D01*
X837700Y-434367D01*
G01X842400Y-438233D02*
X845000D01*
G01Y-435833D02*
X842400D01*
G01X851700Y-439700D02*
Y-431700D01*
X850500Y-433300D01*
G01Y-439700D02*
X852900D01*
G01X857800Y-436367D02*
X858500Y-435433D01*
X859100Y-434900D01*
X859900Y-434633D01*
X860600Y-434900D01*
X861100Y-435433D01*
X861500Y-436233D01*
X861600Y-437167D01*
X861500Y-437967D01*
X861100Y-438767D01*
X860500Y-439433D01*
X859800Y-439700D01*
X859000Y-439433D01*
X858300Y-438634D01*
X857900Y-437433D01*
X857800Y-436100D01*
X858000Y-434367D01*
X858300Y-433433D01*
X858800Y-432500D01*
X859500Y-431833D01*
X860200Y-431700D01*
X860900Y-431967D01*
X861400Y-432633D01*
G01X872700Y-439700D02*
Y-434367D01*
G01Y-435833D02*
X873000Y-435167D01*
X873500Y-434633D01*
X874200Y-434367D01*
X874900Y-434633D01*
X875400Y-435167D01*
X875700Y-435833D01*
Y-439700D01*
G01Y-435833D02*
X876000Y-435167D01*
X876500Y-434633D01*
X877200Y-434367D01*
X877900Y-434633D01*
X878400Y-435167D01*
X878700Y-435967D01*
Y-439700D01*
G01X883700Y-434367D02*
Y-439700D01*
G01Y-432233D02*
X883500Y-432100D01*
Y-431833D01*
X883700Y-431700D01*
X883900Y-431833D01*
Y-432100D01*
X883700Y-432233D01*
G01X891700Y-439700D02*
Y-431700D01*
G01X900200Y-442367D02*
X901200Y-441033D01*
X901700Y-439700D01*
Y-434367D01*
X901200Y-433033D01*
X900200Y-431700D01*
G01X688200Y-419200D02*
Y-427200D01*
G01X686800Y-421867D02*
X689600D01*
G01X694500Y-427200D02*
Y-419200D01*
G01Y-423067D02*
X695000Y-422400D01*
X695500Y-422000D01*
X696300Y-421867D01*
X696900Y-422000D01*
X697600Y-422533D01*
X697900Y-423333D01*
Y-427200D01*
G01X702700Y-423600D02*
X705900D01*
X705600Y-422667D01*
X705100Y-422133D01*
X704400Y-421867D01*
X703700Y-422000D01*
X703100Y-422400D01*
X702700Y-423333D01*
X702500Y-424134D01*
Y-424933D01*
X702700Y-425733D01*
X703200Y-426533D01*
X703800Y-427067D01*
X704500Y-427200D01*
X705200Y-426933D01*
X705900Y-426134D01*
G01X718800Y-427200D02*
Y-421867D01*
G01Y-422933D02*
X719300Y-422400D01*
X719800Y-422000D01*
X720500Y-421867D01*
X721000Y-422000D01*
X721600Y-422400D01*
G01X726700Y-423600D02*
X729900D01*
X729600Y-422667D01*
X729100Y-422133D01*
X728400Y-421867D01*
X727700Y-422000D01*
X727100Y-422400D01*
X726700Y-423333D01*
X726500Y-424134D01*
Y-424933D01*
X726700Y-425733D01*
X727200Y-426533D01*
X727800Y-427067D01*
X728500Y-427200D01*
X729200Y-426933D01*
X729900Y-426134D01*
G01X736200Y-427200D02*
Y-419200D01*
G01X746000Y-427200D02*
Y-421867D01*
G01Y-422800D02*
X745600Y-422267D01*
X745000Y-422000D01*
X744300Y-421867D01*
X743600Y-422133D01*
X743000Y-422667D01*
X742600Y-423467D01*
X742400Y-424533D01*
X742600Y-425600D01*
X743000Y-426400D01*
X743600Y-426933D01*
X744300Y-427200D01*
X745000Y-427067D01*
X745600Y-426667D01*
X746000Y-426134D01*
G01X752200Y-419200D02*
Y-427200D01*
G01X750800Y-421867D02*
X753600D01*
G01X760200D02*
Y-427200D01*
G01Y-419733D02*
X760000Y-419600D01*
Y-419333D01*
X760200Y-419200D01*
X760400Y-419333D01*
Y-419600D01*
X760200Y-419733D01*
G01X766400Y-421867D02*
X768200Y-427200D01*
X770000Y-421867D01*
G01X774700Y-423600D02*
X777900D01*
X777600Y-422667D01*
X777100Y-422133D01*
X776400Y-421867D01*
X775700Y-422000D01*
X775100Y-422400D01*
X774700Y-423333D01*
X774500Y-424134D01*
Y-424933D01*
X774700Y-425733D01*
X775200Y-426533D01*
X775800Y-427067D01*
X776500Y-427200D01*
X777200Y-426933D01*
X777900Y-426134D01*
G01X792200Y-427200D02*
Y-419200D01*
G01X800200Y-427200D02*
X799600Y-427067D01*
X799000Y-426533D01*
X798600Y-425600D01*
X798400Y-424533D01*
X798600Y-423467D01*
X799000Y-422533D01*
X799600Y-422000D01*
X800200Y-421867D01*
X800800Y-422000D01*
X801400Y-422533D01*
X801800Y-423467D01*
X801900Y-424533D01*
X801800Y-425600D01*
X801400Y-426533D01*
X800800Y-427067D01*
X800200Y-427200D01*
G01X809800Y-422533D02*
X809100Y-422000D01*
X808500Y-421867D01*
X807700Y-422133D01*
X807100Y-422667D01*
X806700Y-423600D01*
X806600Y-424533D01*
X806700Y-425467D01*
X807100Y-426267D01*
X807700Y-426933D01*
X808500Y-427200D01*
X809200Y-426933D01*
X809800Y-426400D01*
G01X818000Y-427200D02*
Y-421867D01*
G01Y-422800D02*
X817600Y-422267D01*
X817000Y-422000D01*
X816300Y-421867D01*
X815600Y-422133D01*
X815000Y-422667D01*
X814600Y-423467D01*
X814400Y-424533D01*
X814600Y-425600D01*
X815000Y-426400D01*
X815600Y-426933D01*
X816300Y-427200D01*
X817000Y-427067D01*
X817600Y-426667D01*
X818000Y-426134D01*
G01X824200Y-419200D02*
Y-427200D01*
G01X822800Y-421867D02*
X825600D01*
G01X832200D02*
Y-427200D01*
G01Y-419733D02*
X832000Y-419600D01*
Y-419333D01*
X832200Y-419200D01*
X832400Y-419333D01*
Y-419600D01*
X832200Y-419733D01*
G01X840200Y-427200D02*
X839600Y-427067D01*
X839000Y-426533D01*
X838600Y-425600D01*
X838400Y-424533D01*
X838600Y-423467D01*
X839000Y-422533D01*
X839600Y-422000D01*
X840200Y-421867D01*
X840800Y-422000D01*
X841400Y-422533D01*
X841800Y-423467D01*
X841900Y-424533D01*
X841800Y-425600D01*
X841400Y-426533D01*
X840800Y-427067D01*
X840200Y-427200D01*
G01X846500D02*
Y-421867D01*
G01Y-423200D02*
X846900Y-422533D01*
X847500Y-422000D01*
X848300Y-421867D01*
X849000Y-422000D01*
X849600Y-422533D01*
X849900Y-423467D01*
Y-427200D01*
G01X864200D02*
X863600Y-427067D01*
X863000Y-426533D01*
X862600Y-425600D01*
X862400Y-424533D01*
X862600Y-423467D01*
X863000Y-422533D01*
X863600Y-422000D01*
X864200Y-421867D01*
X864800Y-422000D01*
X865400Y-422533D01*
X865800Y-423467D01*
X865900Y-424533D01*
X865800Y-425600D01*
X865400Y-426533D01*
X864800Y-427067D01*
X864200Y-427200D01*
G01X871600D02*
Y-420400D01*
X871800Y-419733D01*
X872200Y-419333D01*
X872800Y-419200D01*
X873400Y-419467D01*
X873700Y-420133D01*
G01X872500Y-422400D02*
X870500D01*
G01X886500Y-427200D02*
Y-419200D01*
G01Y-423067D02*
X887000Y-422400D01*
X887500Y-422000D01*
X888300Y-421867D01*
X888900Y-422000D01*
X889600Y-422533D01*
X889900Y-423333D01*
Y-427200D01*
G01X896200D02*
X895600Y-427067D01*
X895000Y-426533D01*
X894600Y-425600D01*
X894400Y-424533D01*
X894600Y-423467D01*
X895000Y-422533D01*
X895600Y-422000D01*
X896200Y-421867D01*
X896800Y-422000D01*
X897400Y-422533D01*
X897800Y-423467D01*
X897900Y-424533D01*
X897800Y-425600D01*
X897400Y-426533D01*
X896800Y-427067D01*
X896200Y-427200D01*
G01X904200D02*
Y-419200D01*
G01X910700Y-423600D02*
X913900D01*
X913600Y-422667D01*
X913100Y-422133D01*
X912400Y-421867D01*
X911700Y-422000D01*
X911100Y-422400D01*
X910700Y-423333D01*
X910500Y-424134D01*
Y-424933D01*
X910700Y-425733D01*
X911200Y-426533D01*
X911800Y-427067D01*
X912500Y-427200D01*
X913200Y-426933D01*
X913900Y-426134D01*
G01X928200Y-419200D02*
Y-427200D01*
G01X926800Y-421867D02*
X929600D01*
G01X936200Y-427200D02*
X935600Y-427067D01*
X935000Y-426533D01*
X934600Y-425600D01*
X934400Y-424533D01*
X934600Y-423467D01*
X935000Y-422533D01*
X935600Y-422000D01*
X936200Y-421867D01*
X936800Y-422000D01*
X937400Y-422533D01*
X937800Y-423467D01*
X937900Y-424533D01*
X937800Y-425600D01*
X937400Y-426533D01*
X936800Y-427067D01*
X936200Y-427200D01*
G01X950500D02*
Y-419200D01*
G01Y-423067D02*
X951000Y-422400D01*
X951500Y-422000D01*
X952300Y-421867D01*
X952900Y-422000D01*
X953600Y-422533D01*
X953900Y-423333D01*
Y-427200D01*
G01X960200D02*
X959600Y-427067D01*
X959000Y-426533D01*
X958600Y-425600D01*
X958400Y-424533D01*
X958600Y-423467D01*
X959000Y-422533D01*
X959600Y-422000D01*
X960200Y-421867D01*
X960800Y-422000D01*
X961400Y-422533D01*
X961800Y-423467D01*
X961900Y-424533D01*
X961800Y-425600D01*
X961400Y-426533D01*
X960800Y-427067D01*
X960200Y-427200D01*
G01X968200D02*
Y-419200D01*
G01X974700Y-423600D02*
X977900D01*
X977600Y-422667D01*
X977100Y-422133D01*
X976400Y-421867D01*
X975700Y-422000D01*
X975100Y-422400D01*
X974700Y-423333D01*
X974500Y-424134D01*
Y-424933D01*
X974700Y-425733D01*
X975200Y-426533D01*
X975800Y-427067D01*
X976500Y-427200D01*
X977200Y-426933D01*
X977900Y-426134D01*
G01X834500Y-404700D02*
X836900D01*
G01X835700D02*
Y-412700D01*
G01X834500D02*
X836900D01*
G01X843700Y-404700D02*
Y-412700D01*
G01X842300Y-407367D02*
X845100D01*
G01X850200Y-409100D02*
X853400D01*
X853100Y-408167D01*
X852600Y-407633D01*
X851900Y-407367D01*
X851200Y-407500D01*
X850600Y-407900D01*
X850200Y-408833D01*
X850000Y-409634D01*
Y-410433D01*
X850200Y-411233D01*
X850700Y-412033D01*
X851300Y-412567D01*
X852000Y-412700D01*
X852700Y-412433D01*
X853400Y-411634D01*
G01X856700Y-412700D02*
Y-407367D01*
G01Y-408833D02*
X857000Y-408167D01*
X857500Y-407633D01*
X858200Y-407367D01*
X858900Y-407633D01*
X859400Y-408167D01*
X859700Y-408833D01*
Y-412700D01*
G01Y-408833D02*
X860000Y-408167D01*
X860500Y-407633D01*
X861200Y-407367D01*
X861900Y-407633D01*
X862400Y-408167D01*
X862700Y-408967D01*
Y-412700D01*
G01X866200Y-411767D02*
X866700Y-412300D01*
X867400Y-412700D01*
X868000D01*
X868600Y-412433D01*
X869000Y-412033D01*
X869200Y-411500D01*
X869100Y-410700D01*
X868700Y-410300D01*
X866900Y-409500D01*
X866500Y-408567D01*
X866700Y-407900D01*
X867100Y-407500D01*
X867700Y-407367D01*
X868300Y-407500D01*
X868900Y-407900D01*
G01X1083100Y-524833D02*
X1085500D01*
G01X1084200Y-523100D02*
Y-526567D01*
G01X1092200Y-519500D02*
X1091400Y-519767D01*
X1090800Y-520433D01*
X1090400Y-521233D01*
X1090100Y-522300D01*
X1090000Y-523500D01*
X1090100Y-524700D01*
X1090400Y-525767D01*
X1090800Y-526567D01*
X1091400Y-527233D01*
X1092200Y-527500D01*
X1093000Y-527233D01*
X1093600Y-526567D01*
X1094000Y-525767D01*
X1094300Y-524700D01*
X1094400Y-523500D01*
X1094300Y-522300D01*
X1094000Y-521233D01*
X1093600Y-520433D01*
X1093000Y-519767D01*
X1092200Y-519500D01*
G01X1100200Y-527767D02*
X1100000Y-527633D01*
Y-527367D01*
X1100200Y-527233D01*
X1100400Y-527367D01*
Y-527633D01*
X1100200Y-527767D01*
G01X1108200Y-519500D02*
X1107400Y-519767D01*
X1106800Y-520433D01*
X1106400Y-521233D01*
X1106100Y-522300D01*
X1106000Y-523500D01*
X1106100Y-524700D01*
X1106400Y-525767D01*
X1106800Y-526567D01*
X1107400Y-527233D01*
X1108200Y-527500D01*
X1109000Y-527233D01*
X1109600Y-526567D01*
X1110000Y-525767D01*
X1110300Y-524700D01*
X1110400Y-523500D01*
X1110300Y-522300D01*
X1110000Y-521233D01*
X1109600Y-520433D01*
X1109000Y-519767D01*
X1108200Y-519500D01*
G01X1116000Y-527500D02*
X1116200Y-525767D01*
X1116500Y-524300D01*
X1116900Y-522967D01*
X1117400Y-521500D01*
X1118200Y-519500D01*
X1114200D01*
G01X1122000Y-526300D02*
X1122600Y-526967D01*
X1123300Y-527367D01*
X1124200Y-527500D01*
X1125100Y-527233D01*
X1125800Y-526700D01*
X1126300Y-525767D01*
X1126400Y-524700D01*
X1126200Y-523633D01*
X1125700Y-522967D01*
X1125000Y-522433D01*
X1124300Y-522300D01*
X1123600Y-522433D01*
X1122700Y-522967D01*
X1123000Y-519500D01*
X1125700D01*
G01X1130400Y-527767D02*
X1134000Y-519500D01*
G01X1138900Y-524833D02*
X1141500D01*
G01X1148200Y-519500D02*
X1147400Y-519767D01*
X1146800Y-520433D01*
X1146400Y-521233D01*
X1146100Y-522300D01*
X1146000Y-523500D01*
X1146100Y-524700D01*
X1146400Y-525767D01*
X1146800Y-526567D01*
X1147400Y-527233D01*
X1148200Y-527500D01*
X1149000Y-527233D01*
X1149600Y-526567D01*
X1150000Y-525767D01*
X1150300Y-524700D01*
X1150400Y-523500D01*
X1150300Y-522300D01*
X1150000Y-521233D01*
X1149600Y-520433D01*
X1149000Y-519767D01*
X1148200Y-519500D01*
G01X1153200Y-527500D02*
Y-522167D01*
G01Y-523633D02*
X1153500Y-522967D01*
X1154000Y-522433D01*
X1154700Y-522167D01*
X1155400Y-522433D01*
X1155900Y-522967D01*
X1156200Y-523633D01*
Y-527500D01*
G01Y-523633D02*
X1156500Y-522967D01*
X1157000Y-522433D01*
X1157700Y-522167D01*
X1158400Y-522433D01*
X1158900Y-522967D01*
X1159200Y-523767D01*
Y-527500D01*
G01X1161200D02*
Y-522167D01*
G01Y-523633D02*
X1161500Y-522967D01*
X1162000Y-522433D01*
X1162700Y-522167D01*
X1163400Y-522433D01*
X1163900Y-522967D01*
X1164200Y-523633D01*
Y-527500D01*
G01Y-523633D02*
X1164500Y-522967D01*
X1165000Y-522433D01*
X1165700Y-522167D01*
X1166400Y-522433D01*
X1166900Y-522967D01*
X1167200Y-523767D01*
Y-527500D01*
G01X1088700Y-577100D02*
Y-569100D01*
X1087500Y-570700D01*
G01Y-577100D02*
X1089900D01*
G01X1096700Y-577367D02*
X1096500Y-577233D01*
Y-576967D01*
X1096700Y-576833D01*
X1096900Y-576967D01*
Y-577233D01*
X1096700Y-577367D01*
G01X1104700Y-569100D02*
X1103900Y-569367D01*
X1103300Y-570033D01*
X1102900Y-570833D01*
X1102600Y-571900D01*
X1102500Y-573100D01*
X1102600Y-574300D01*
X1102900Y-575367D01*
X1103300Y-576167D01*
X1103900Y-576833D01*
X1104700Y-577100D01*
X1105500Y-576833D01*
X1106100Y-576167D01*
X1106500Y-575367D01*
X1106800Y-574300D01*
X1106900Y-573100D01*
X1106800Y-571900D01*
X1106500Y-570833D01*
X1106100Y-570033D01*
X1105500Y-569367D01*
X1104700Y-569100D01*
G01X1109700Y-577100D02*
Y-571767D01*
G01Y-573233D02*
X1110000Y-572567D01*
X1110500Y-572033D01*
X1111200Y-571767D01*
X1111900Y-572033D01*
X1112400Y-572567D01*
X1112700Y-573233D01*
Y-577100D01*
G01Y-573233D02*
X1113000Y-572567D01*
X1113500Y-572033D01*
X1114200Y-571767D01*
X1114900Y-572033D01*
X1115400Y-572567D01*
X1115700Y-573367D01*
Y-577100D01*
G01X1120700Y-571767D02*
Y-577100D01*
G01Y-569633D02*
X1120500Y-569500D01*
Y-569233D01*
X1120700Y-569100D01*
X1120900Y-569233D01*
Y-569500D01*
X1120700Y-569633D01*
G01X1128700Y-577100D02*
Y-569100D01*
G01X1141700Y-577100D02*
Y-571767D01*
G01Y-573233D02*
X1142000Y-572567D01*
X1142500Y-572033D01*
X1143200Y-571767D01*
X1143900Y-572033D01*
X1144400Y-572567D01*
X1144700Y-573233D01*
Y-577100D01*
G01Y-573233D02*
X1145000Y-572567D01*
X1145500Y-572033D01*
X1146200Y-571767D01*
X1146900Y-572033D01*
X1147400Y-572567D01*
X1147700Y-573367D01*
Y-577100D01*
G01X1154500D02*
Y-571767D01*
G01Y-572700D02*
X1154100Y-572167D01*
X1153500Y-571900D01*
X1152800Y-571767D01*
X1152100Y-572033D01*
X1151500Y-572567D01*
X1151100Y-573367D01*
X1150900Y-574433D01*
X1151100Y-575500D01*
X1151500Y-576300D01*
X1152100Y-576833D01*
X1152800Y-577100D01*
X1153500Y-576967D01*
X1154100Y-576567D01*
X1154500Y-576034D01*
G01X1159200Y-571767D02*
X1162200Y-577100D01*
G01Y-571767D02*
X1159200Y-577100D01*
G01X1094700Y-403700D02*
Y-411700D01*
G01X1092400Y-403700D02*
X1097000D01*
G01X1102700Y-411700D02*
X1102100Y-411567D01*
X1101500Y-411033D01*
X1101100Y-410100D01*
X1100900Y-409033D01*
X1101100Y-407967D01*
X1101500Y-407033D01*
X1102100Y-406500D01*
X1102700Y-406367D01*
X1103300Y-406500D01*
X1103900Y-407033D01*
X1104300Y-407967D01*
X1104400Y-409033D01*
X1104300Y-410100D01*
X1103900Y-411033D01*
X1103300Y-411567D01*
X1102700Y-411700D01*
G01X1110700D02*
Y-403700D01*
G01X1117200Y-408100D02*
X1120400D01*
X1120100Y-407167D01*
X1119600Y-406633D01*
X1118900Y-406367D01*
X1118200Y-406500D01*
X1117600Y-406900D01*
X1117200Y-407833D01*
X1117000Y-408634D01*
Y-409433D01*
X1117200Y-410233D01*
X1117700Y-411033D01*
X1118300Y-411567D01*
X1119000Y-411700D01*
X1119700Y-411433D01*
X1120400Y-410634D01*
G01X1125300Y-411700D02*
Y-406367D01*
G01Y-407433D02*
X1125800Y-406900D01*
X1126300Y-406500D01*
X1127000Y-406367D01*
X1127500Y-406500D01*
X1128100Y-406900D01*
G01X1136500Y-411700D02*
Y-406367D01*
G01Y-407300D02*
X1136100Y-406767D01*
X1135500Y-406500D01*
X1134800Y-406367D01*
X1134100Y-406633D01*
X1133500Y-407167D01*
X1133100Y-407967D01*
X1132900Y-409033D01*
X1133100Y-410100D01*
X1133500Y-410900D01*
X1134100Y-411433D01*
X1134800Y-411700D01*
X1135500Y-411567D01*
X1136100Y-411167D01*
X1136500Y-410634D01*
G01X1141000Y-411700D02*
Y-406367D01*
G01Y-407700D02*
X1141400Y-407033D01*
X1142000Y-406500D01*
X1142800Y-406367D01*
X1143500Y-406500D01*
X1144100Y-407033D01*
X1144400Y-407967D01*
Y-411700D01*
G01X1152300Y-407033D02*
X1151600Y-406500D01*
X1151000Y-406367D01*
X1150200Y-406633D01*
X1149600Y-407167D01*
X1149200Y-408100D01*
X1149100Y-409033D01*
X1149200Y-409967D01*
X1149600Y-410767D01*
X1150200Y-411433D01*
X1151000Y-411700D01*
X1151700Y-411433D01*
X1152300Y-410900D01*
G01X1157200Y-408100D02*
X1160400D01*
X1160100Y-407167D01*
X1159600Y-406633D01*
X1158900Y-406367D01*
X1158200Y-406500D01*
X1157600Y-406900D01*
X1157200Y-407833D01*
X1157000Y-408634D01*
Y-409433D01*
X1157200Y-410233D01*
X1157700Y-411033D01*
X1158300Y-411567D01*
X1159000Y-411700D01*
X1159700Y-411433D01*
X1160400Y-410634D01*
G01X1099600Y-549533D02*
X1102000D01*
G01X1100700Y-547800D02*
Y-551267D01*
G01X1106900Y-552467D02*
X1110500Y-544200D01*
G01X1115400Y-549533D02*
X1118000D01*
G01X1122500Y-551000D02*
X1123100Y-551667D01*
X1123800Y-552067D01*
X1124700Y-552200D01*
X1125600Y-551933D01*
X1126300Y-551400D01*
X1126800Y-550467D01*
X1126900Y-549400D01*
X1126700Y-548333D01*
X1126200Y-547667D01*
X1125500Y-547133D01*
X1124800Y-547000D01*
X1124100Y-547133D01*
X1123200Y-547667D01*
X1123500Y-544200D01*
X1126200D01*
G01X1129700Y-552200D02*
Y-546867D01*
G01Y-548333D02*
X1130000Y-547667D01*
X1130500Y-547133D01*
X1131200Y-546867D01*
X1131900Y-547133D01*
X1132400Y-547667D01*
X1132700Y-548333D01*
Y-552200D01*
G01Y-548333D02*
X1133000Y-547667D01*
X1133500Y-547133D01*
X1134200Y-546867D01*
X1134900Y-547133D01*
X1135400Y-547667D01*
X1135700Y-548467D01*
Y-552200D01*
G01X1140700Y-546867D02*
Y-552200D01*
G01Y-544733D02*
X1140500Y-544600D01*
Y-544333D01*
X1140700Y-544200D01*
X1140900Y-544333D01*
Y-544600D01*
X1140700Y-544733D01*
G01X1148700Y-552200D02*
Y-544200D01*
G01X1099600Y-562533D02*
X1102000D01*
G01X1100700Y-560800D02*
Y-564267D01*
G01X1106900Y-565467D02*
X1110500Y-557200D01*
G01X1115400Y-562533D02*
X1118000D01*
G01X1122500Y-564000D02*
X1123100Y-564667D01*
X1123800Y-565067D01*
X1124700Y-565200D01*
X1125600Y-564933D01*
X1126300Y-564400D01*
X1126800Y-563467D01*
X1126900Y-562400D01*
X1126700Y-561333D01*
X1126200Y-560667D01*
X1125500Y-560133D01*
X1124800Y-560000D01*
X1124100Y-560133D01*
X1123200Y-560667D01*
X1123500Y-557200D01*
X1126200D01*
G01X1129700Y-565200D02*
Y-559867D01*
G01Y-561333D02*
X1130000Y-560667D01*
X1130500Y-560133D01*
X1131200Y-559867D01*
X1131900Y-560133D01*
X1132400Y-560667D01*
X1132700Y-561333D01*
Y-565200D01*
G01Y-561333D02*
X1133000Y-560667D01*
X1133500Y-560133D01*
X1134200Y-559867D01*
X1134900Y-560133D01*
X1135400Y-560667D01*
X1135700Y-561467D01*
Y-565200D01*
G01X1140700Y-559867D02*
Y-565200D01*
G01Y-557733D02*
X1140500Y-557600D01*
Y-557333D01*
X1140700Y-557200D01*
X1140900Y-557333D01*
Y-557600D01*
X1140700Y-557733D01*
G01X1148700Y-565200D02*
Y-557200D01*
G01X1099600Y-537033D02*
X1102000D01*
G01X1100700Y-535300D02*
Y-538767D01*
G01X1106900Y-539967D02*
X1110500Y-531700D01*
G01X1115400Y-537033D02*
X1118000D01*
G01X1124700Y-531700D02*
X1123900Y-531967D01*
X1123300Y-532633D01*
X1122900Y-533433D01*
X1122600Y-534500D01*
X1122500Y-535700D01*
X1122600Y-536900D01*
X1122900Y-537967D01*
X1123300Y-538767D01*
X1123900Y-539433D01*
X1124700Y-539700D01*
X1125500Y-539433D01*
X1126100Y-538767D01*
X1126500Y-537967D01*
X1126800Y-536900D01*
X1126900Y-535700D01*
X1126800Y-534500D01*
X1126500Y-533433D01*
X1126100Y-532633D01*
X1125500Y-531967D01*
X1124700Y-531700D01*
G01X1132700Y-539967D02*
X1132500Y-539833D01*
Y-539567D01*
X1132700Y-539433D01*
X1132900Y-539567D01*
Y-539833D01*
X1132700Y-539967D01*
G01X1140700Y-531700D02*
X1139900Y-531967D01*
X1139300Y-532633D01*
X1138900Y-533433D01*
X1138600Y-534500D01*
X1138500Y-535700D01*
X1138600Y-536900D01*
X1138900Y-537967D01*
X1139300Y-538767D01*
X1139900Y-539433D01*
X1140700Y-539700D01*
X1141500Y-539433D01*
X1142100Y-538767D01*
X1142500Y-537967D01*
X1142800Y-536900D01*
X1142900Y-535700D01*
X1142800Y-534500D01*
X1142500Y-533433D01*
X1142100Y-532633D01*
X1141500Y-531967D01*
X1140700Y-531700D01*
G01X1146500Y-538500D02*
X1147100Y-539167D01*
X1147800Y-539567D01*
X1148700Y-539700D01*
X1149600Y-539433D01*
X1150300Y-538900D01*
X1150800Y-537967D01*
X1150900Y-536900D01*
X1150700Y-535833D01*
X1150200Y-535167D01*
X1149500Y-534633D01*
X1148800Y-534500D01*
X1148100Y-534633D01*
X1147200Y-535167D01*
X1147500Y-531700D01*
X1150200D01*
G01X1153700Y-539700D02*
Y-534367D01*
G01Y-535833D02*
X1154000Y-535167D01*
X1154500Y-534633D01*
X1155200Y-534367D01*
X1155900Y-534633D01*
X1156400Y-535167D01*
X1156700Y-535833D01*
Y-539700D01*
G01Y-535833D02*
X1157000Y-535167D01*
X1157500Y-534633D01*
X1158200Y-534367D01*
X1158900Y-534633D01*
X1159400Y-535167D01*
X1159700Y-535967D01*
Y-539700D01*
G01X1161700D02*
Y-534367D01*
G01Y-535833D02*
X1162000Y-535167D01*
X1162500Y-534633D01*
X1163200Y-534367D01*
X1163900Y-534633D01*
X1164400Y-535167D01*
X1164700Y-535833D01*
Y-539700D01*
G01Y-535833D02*
X1165000Y-535167D01*
X1165500Y-534633D01*
X1166200Y-534367D01*
X1166900Y-534633D01*
X1167400Y-535167D01*
X1167700Y-535967D01*
Y-539700D01*
G01X1099600Y-474533D02*
X1102000D01*
G01X1100700Y-472800D02*
Y-476267D01*
G01X1106900Y-477467D02*
X1110500Y-469200D01*
G01X1115400Y-474533D02*
X1118000D01*
G01X1122800Y-470533D02*
X1123400Y-469733D01*
X1124100Y-469333D01*
X1124900Y-469200D01*
X1125900Y-469467D01*
X1126600Y-470133D01*
X1126800Y-470933D01*
X1126700Y-471734D01*
X1126300Y-472400D01*
X1124300Y-473733D01*
X1123400Y-474667D01*
X1122800Y-476000D01*
X1122600Y-477200D01*
X1126800D01*
G01X1129700D02*
Y-471867D01*
G01Y-473333D02*
X1130000Y-472667D01*
X1130500Y-472133D01*
X1131200Y-471867D01*
X1131900Y-472133D01*
X1132400Y-472667D01*
X1132700Y-473333D01*
Y-477200D01*
G01Y-473333D02*
X1133000Y-472667D01*
X1133500Y-472133D01*
X1134200Y-471867D01*
X1134900Y-472133D01*
X1135400Y-472667D01*
X1135700Y-473467D01*
Y-477200D01*
G01X1140700Y-471867D02*
Y-477200D01*
G01Y-469733D02*
X1140500Y-469600D01*
Y-469333D01*
X1140700Y-469200D01*
X1140900Y-469333D01*
Y-469600D01*
X1140700Y-469733D01*
G01X1148700Y-477200D02*
Y-469200D01*
G01X1099600Y-512533D02*
X1102000D01*
G01X1100700Y-510800D02*
Y-514267D01*
G01X1106900Y-515467D02*
X1110500Y-507200D01*
G01X1115400Y-512533D02*
X1118000D01*
G01X1122800Y-508533D02*
X1123400Y-507733D01*
X1124100Y-507333D01*
X1124900Y-507200D01*
X1125900Y-507467D01*
X1126600Y-508133D01*
X1126800Y-508933D01*
X1126700Y-509734D01*
X1126300Y-510400D01*
X1124300Y-511733D01*
X1123400Y-512667D01*
X1122800Y-514000D01*
X1122600Y-515200D01*
X1126800D01*
G01X1129700D02*
Y-509867D01*
G01Y-511333D02*
X1130000Y-510667D01*
X1130500Y-510133D01*
X1131200Y-509867D01*
X1131900Y-510133D01*
X1132400Y-510667D01*
X1132700Y-511333D01*
Y-515200D01*
G01Y-511333D02*
X1133000Y-510667D01*
X1133500Y-510133D01*
X1134200Y-509867D01*
X1134900Y-510133D01*
X1135400Y-510667D01*
X1135700Y-511467D01*
Y-515200D01*
G01X1140700Y-509867D02*
Y-515200D01*
G01Y-507733D02*
X1140500Y-507600D01*
Y-507333D01*
X1140700Y-507200D01*
X1140900Y-507333D01*
Y-507600D01*
X1140700Y-507733D01*
G01X1148700Y-515200D02*
Y-507200D01*
G01X1099600Y-492033D02*
X1102000D01*
G01X1100700Y-490300D02*
Y-493767D01*
G01X1106900Y-494967D02*
X1110500Y-486700D01*
G01X1115400Y-492033D02*
X1118000D01*
G01X1122500Y-493100D02*
X1123100Y-494033D01*
X1123900Y-494567D01*
X1124800Y-494700D01*
X1125600Y-494567D01*
X1126400Y-493900D01*
X1126900Y-493100D01*
X1127000Y-492300D01*
X1126800Y-491367D01*
X1126100Y-490700D01*
X1125400Y-490433D01*
X1124500D01*
G01X1125400D02*
X1126000Y-490033D01*
X1126500Y-489367D01*
X1126700Y-488567D01*
X1126500Y-487767D01*
X1126000Y-487100D01*
X1125100Y-486700D01*
X1124200Y-486833D01*
X1123300Y-487367D01*
G01X1129700Y-494700D02*
Y-489367D01*
G01Y-490833D02*
X1130000Y-490167D01*
X1130500Y-489633D01*
X1131200Y-489367D01*
X1131900Y-489633D01*
X1132400Y-490167D01*
X1132700Y-490833D01*
Y-494700D01*
G01Y-490833D02*
X1133000Y-490167D01*
X1133500Y-489633D01*
X1134200Y-489367D01*
X1134900Y-489633D01*
X1135400Y-490167D01*
X1135700Y-490967D01*
Y-494700D01*
G01X1140700Y-489367D02*
Y-494700D01*
G01Y-487233D02*
X1140500Y-487100D01*
Y-486833D01*
X1140700Y-486700D01*
X1140900Y-486833D01*
Y-487100D01*
X1140700Y-487233D01*
G01X1148700Y-494700D02*
Y-486700D01*
G01X1099600Y-424533D02*
X1102000D01*
G01X1100700Y-422800D02*
Y-426267D01*
G01X1106900Y-427467D02*
X1110500Y-419200D01*
G01X1115400Y-424533D02*
X1118000D01*
G01X1122500Y-425600D02*
X1123100Y-426533D01*
X1123900Y-427067D01*
X1124800Y-427200D01*
X1125600Y-427067D01*
X1126400Y-426400D01*
X1126900Y-425600D01*
X1127000Y-424800D01*
X1126800Y-423867D01*
X1126100Y-423200D01*
X1125400Y-422933D01*
X1124500D01*
G01X1125400D02*
X1126000Y-422533D01*
X1126500Y-421867D01*
X1126700Y-421067D01*
X1126500Y-420267D01*
X1126000Y-419600D01*
X1125100Y-419200D01*
X1124200Y-419333D01*
X1123300Y-419867D01*
G01X1129700Y-427200D02*
Y-421867D01*
G01Y-423333D02*
X1130000Y-422667D01*
X1130500Y-422133D01*
X1131200Y-421867D01*
X1131900Y-422133D01*
X1132400Y-422667D01*
X1132700Y-423333D01*
Y-427200D01*
G01Y-423333D02*
X1133000Y-422667D01*
X1133500Y-422133D01*
X1134200Y-421867D01*
X1134900Y-422133D01*
X1135400Y-422667D01*
X1135700Y-423467D01*
Y-427200D01*
G01X1140700Y-421867D02*
Y-427200D01*
G01Y-419733D02*
X1140500Y-419600D01*
Y-419333D01*
X1140700Y-419200D01*
X1140900Y-419333D01*
Y-419600D01*
X1140700Y-419733D01*
G01X1148700Y-427200D02*
Y-419200D01*
G01X1099600Y-449033D02*
X1102000D01*
G01X1100700Y-447300D02*
Y-450767D01*
G01X1108700Y-451700D02*
Y-443700D01*
X1107500Y-445300D01*
G01Y-451700D02*
X1109900D01*
G01X1114900Y-451967D02*
X1118500Y-443700D01*
G01X1123400Y-449033D02*
X1126000D01*
G01X1130500Y-450100D02*
X1131100Y-451033D01*
X1131900Y-451567D01*
X1132800Y-451700D01*
X1133600Y-451567D01*
X1134400Y-450900D01*
X1134900Y-450100D01*
X1135000Y-449300D01*
X1134800Y-448367D01*
X1134100Y-447700D01*
X1133400Y-447433D01*
X1132500D01*
G01X1133400D02*
X1134000Y-447033D01*
X1134500Y-446367D01*
X1134700Y-445567D01*
X1134500Y-444767D01*
X1134000Y-444100D01*
X1133100Y-443700D01*
X1132200Y-443833D01*
X1131300Y-444367D01*
G01X1137700Y-451700D02*
Y-446367D01*
G01Y-447833D02*
X1138000Y-447167D01*
X1138500Y-446633D01*
X1139200Y-446367D01*
X1139900Y-446633D01*
X1140400Y-447167D01*
X1140700Y-447833D01*
Y-451700D01*
G01Y-447833D02*
X1141000Y-447167D01*
X1141500Y-446633D01*
X1142200Y-446367D01*
X1142900Y-446633D01*
X1143400Y-447167D01*
X1143700Y-447967D01*
Y-451700D01*
G01X1148700Y-446367D02*
Y-451700D01*
G01Y-444233D02*
X1148500Y-444100D01*
Y-443833D01*
X1148700Y-443700D01*
X1148900Y-443833D01*
Y-444100D01*
X1148700Y-444233D01*
G01X1156700Y-451700D02*
Y-443700D01*
G01X1099600Y-437033D02*
X1102000D01*
G01X1100700Y-435300D02*
Y-438767D01*
G01X1106800Y-433033D02*
X1107400Y-432233D01*
X1108100Y-431833D01*
X1108900Y-431700D01*
X1109900Y-431967D01*
X1110600Y-432633D01*
X1110800Y-433433D01*
X1110700Y-434234D01*
X1110300Y-434900D01*
X1108300Y-436233D01*
X1107400Y-437167D01*
X1106800Y-438500D01*
X1106600Y-439700D01*
X1110800D01*
G01X1114900Y-439967D02*
X1118500Y-431700D01*
G01X1123400Y-437033D02*
X1126000D01*
G01X1133900Y-439700D02*
Y-431700D01*
X1130200Y-437433D01*
X1135200D01*
G01X1137700Y-439700D02*
Y-434367D01*
G01Y-435833D02*
X1138000Y-435167D01*
X1138500Y-434633D01*
X1139200Y-434367D01*
X1139900Y-434633D01*
X1140400Y-435167D01*
X1140700Y-435833D01*
Y-439700D01*
G01Y-435833D02*
X1141000Y-435167D01*
X1141500Y-434633D01*
X1142200Y-434367D01*
X1142900Y-434633D01*
X1143400Y-435167D01*
X1143700Y-435967D01*
Y-439700D01*
G01X1148700Y-434367D02*
Y-439700D01*
G01Y-432233D02*
X1148500Y-432100D01*
Y-431833D01*
X1148700Y-431700D01*
X1148900Y-431833D01*
Y-432100D01*
X1148700Y-432233D01*
G01X1156700Y-439700D02*
Y-431700D01*
G01X-138200Y161700D02*
Y-707100D01*
X1402700D01*
Y161700D01*
X-138200D01*
G01Y-256700D02*
X1402700D01*
G01X60800Y-507400D02*
X85400D01*
X85600Y-507200D01*
X83200Y-504800D01*
G01X47300Y-469900D02*
Y-448700D01*
X47200Y-448600D01*
X42800Y-453000D01*
G01X47500Y-448800D02*
Y-448900D01*
X51600Y-453000D01*
G01X85300Y-448700D02*
X25500D01*
X25400Y-448600D01*
G01X48300Y-409200D02*
X48400D01*
X51500Y-406100D01*
G01X48300Y-408800D02*
X48700D01*
G01X48400Y-388900D02*
Y-408700D01*
X48100Y-409000D01*
X45100Y-406000D01*
G01X85200Y-409200D02*
X25300D01*
G01X43873Y-3903D02*
X43883Y-15903D01*
G01X43873Y-3903D02*
X67894Y-27883D01*
X67900Y-67200D01*
G01X43873Y-3903D02*
X55873Y-3893D01*
G01X112400Y-534200D02*
X112200D01*
X109600Y-536800D01*
G01X73300Y-534200D02*
X112200D01*
X112500Y-533900D01*
X109900Y-531300D01*
G01X112500Y-501800D02*
Y-549400D01*
G01X91700Y-507300D02*
Y-507500D01*
X94200Y-510000D01*
G01X107000Y-507400D02*
X91800D01*
X91700Y-507300D01*
X94300Y-504700D01*
G01X85400Y-507200D02*
Y-507500D01*
X83500Y-509400D01*
G01X91600Y-464600D02*
Y-513600D01*
X91500Y-513700D01*
G01X85600Y-464800D02*
Y-514000D01*
X85500Y-514100D01*
G01X85600Y-390100D02*
Y-318100D01*
G01X85900Y-335300D02*
Y-335400D01*
X87700Y-337200D01*
G01X99400Y-335300D02*
X86000D01*
X85800Y-335100D01*
X87900Y-333000D01*
G01X101320Y-22730D02*
X143320D01*
G01X101320D02*
X109320Y-30730D01*
G01X101320Y-22730D02*
X109320Y-14730D01*
G01X89780Y3840D02*
X113780Y27840D01*
X145780D01*
G01X89780Y3840D02*
Y15840D01*
G01Y3840D02*
X101780D01*
G01X137600Y-533800D02*
Y-533900D01*
X140800Y-537100D01*
G01X168800Y-533900D02*
X137700D01*
X137500Y-533700D01*
X140500Y-530700D01*
G01X137500Y-501300D02*
Y-549300D01*
G01Y-501800D02*
X231900D01*
X232500Y-502400D01*
G01X136500Y-355600D02*
X225800D01*
X226300Y-355100D01*
G01X164700Y-393200D02*
Y-320700D01*
X164800Y-320600D01*
G01X164700Y-335000D02*
Y-335100D01*
X162100Y-337700D01*
G01X143700Y-335100D02*
X164600D01*
X164800Y-334900D01*
X162000Y-332100D01*
X161900D01*
G01X190500Y-501300D02*
X190700D01*
X194300Y-497700D01*
G01X190400Y-501400D02*
X189900D01*
X186000Y-497500D01*
G01X190300Y-447500D02*
Y-501200D01*
X189700Y-501800D01*
G01X189200Y-355800D02*
X192400Y-359000D01*
G01X189100Y-355700D02*
X185700Y-359100D01*
G01X189200Y-356200D02*
Y-407400D01*
X189700Y-407900D01*
G01X505000Y161800D02*
Y-707100D01*
G01X528700Y-579700D02*
X1181700D01*
Y-399700D01*
X528700D01*
Y-579700D01*
G01X1181700Y-567200D02*
X528700D01*
G01Y-542200D02*
Y-554700D01*
X556700D01*
Y-542200D01*
G01X528700Y-517200D02*
Y-529700D01*
X556700D01*
Y-517200D01*
G01X528700Y-529700D02*
Y-542200D01*
X556700D01*
Y-529700D01*
G01Y-579700D02*
Y-554700D01*
G01Y-579700D02*
X670700D01*
Y-416700D01*
G01X528700Y-504700D02*
Y-517200D01*
X556700D01*
Y-504700D01*
G01X528700Y-492200D02*
Y-504700D01*
X556700D01*
Y-492200D01*
G01X528700Y-467200D02*
Y-479700D01*
X556700D01*
Y-467200D01*
G01X556200Y-439200D02*
X556700D01*
Y-495700D01*
G01X528700Y-442200D02*
Y-454700D01*
X556700D01*
Y-442200D01*
G01X528700Y-429700D02*
Y-442200D01*
X556700D01*
Y-429700D01*
G01X528700Y-417200D02*
Y-429700D01*
X556700D01*
Y-417200D01*
G01X1181700D02*
X528700D01*
G01X537700Y-399700D02*
X1181700D01*
Y-417200D01*
X528700D01*
Y-399700D01*
X537700D01*
G01X556700Y-417200D02*
Y-399700D01*
G01Y-429700D02*
X670700D01*
Y-417200D01*
G01X1181700Y-554700D02*
X670700D01*
G01X1181700Y-542200D02*
X670700D01*
G01Y-529700D02*
X1181700D01*
Y-517200D01*
G01D02*
X670700D01*
G01X1181700Y-504700D02*
X670700D01*
G01X1181700Y-479700D02*
X670700D01*
G01X1181700Y-442200D02*
X670700D01*
G01X1181700Y-454700D02*
X670700D01*
G01Y-417200D02*
Y-399700D01*
G01X1181700Y-429700D02*
X670700D01*
G01X1080200Y-579700D02*
Y-399700D01*
G01X1090200Y-554700D02*
X1181700D01*
Y-542200D01*
G01X1090200D02*
X1181700D01*
Y-529700D01*
G01X1090200Y-517200D02*
X1181700D01*
Y-504700D01*
G01X1090200D02*
X1181700D01*
Y-479700D01*
G01X1090200D02*
X1181700D01*
Y-442200D01*
G01X1090200Y-454700D02*
X1181700D01*
Y-442200D01*
G01X1090200D02*
X1181700D01*
Y-429700D01*
G01X1090200D02*
X1181700D01*
Y-417200D01*
G01X1162900Y-256700D02*
Y-256600D01*
M02*
